(kicad_sch
	(version 20250114)
	(generator "eeschema")
	(generator_version "9.0")
	(paper "A3")
	(title_block
		(title "Kintex 410T devboard")
		(date "2024-04-03")
		(rev "1.1.2")
	)
	(text "Dual phase"
		(exclude_from_sim no)
		(at 121.92 194.31 0)
		(effects
			(font
				(size 1.27 1.27)
			)
			(justify left bottom)
		)
	)
	(text "X"
		(exclude_from_sim no)
		(at 34.925 193.04 0)
		(effects
			(font
				(size 1.27 1.27)
			)
			(justify left bottom)
		)
	)
	(text "MGTAVCC"
		(exclude_from_sim no)
		(at 16.51 96.52 0)
		(effects
			(font
				(size 1.27 1.27)
			)
			(justify left bottom)
		)
	)
	(text "Always-ON +3V3 LDO"
		(exclude_from_sim no)
		(at 13.335 16.51 0)
		(effects
			(font
				(size 1.27 1.27)
				(thickness 0.254)
				(bold yes)
			)
			(justify left bottom)
		)
	)
	(text "I2C: 0x68"
		(exclude_from_sim no)
		(at 74.295 151.765 0)
		(effects
			(font
				(size 1.27 1.27)
			)
			(justify left bottom)
		)
	)
	(text "Soft start delay time slot"
		(exclude_from_sim no)
		(at 17.78 182.88 0)
		(effects
			(font
				(size 1.27 1.27)
			)
			(justify left bottom)
		)
	)
	(text "Mount for CW310 compatibility"
		(exclude_from_sim no)
		(at 85.725 279.4 0)
		(effects
			(font
				(size 1.27 1.27)
			)
			(justify left bottom)
		)
	)
	(text "+1V8"
		(exclude_from_sim no)
		(at 17.78 99.06 0)
		(effects
			(font
				(size 1.27 1.27)
			)
			(justify left bottom)
		)
	)
	(text "ADC Reference"
		(exclude_from_sim no)
		(at 275.59 144.78 0)
		(effects
			(font
				(size 1.27 1.27)
				(thickness 0.254)
				(bold yes)
			)
			(justify left bottom)
		)
	)
	(text "NOTE:\npopulate C339 and\nremove R308 when \n\"Button controller\" \nis not pupulated"
		(exclude_from_sim no)
		(at 189.865 64.135 0)
		(effects
			(font
				(size 1.27 1.27)
			)
			(justify left bottom)
		)
	)
	(text "MGTAVTT"
		(exclude_from_sim no)
		(at 16.51 104.14 0)
		(effects
			(font
				(size 1.27 1.27)
			)
			(justify left bottom)
		)
	)
	(text "X"
		(exclude_from_sim no)
		(at 27.94 96.52 0)
		(effects
			(font
				(size 1.27 1.27)
			)
			(justify left bottom)
		)
	)
	(text "NOTE:\noptional \nexternal divider "
		(exclude_from_sim no)
		(at 169.545 113.03 0)
		(effects
			(font
				(size 1.27 1.27)
			)
			(justify left bottom)
		)
	)
	(text "NOTE:\nremote sense"
		(exclude_from_sim no)
		(at 203.2 107.315 0)
		(effects
			(font
				(size 1.27 1.27)
			)
			(justify left bottom)
		)
	)
	(text "NOTE:\noptional \nexternal divider "
		(exclude_from_sim no)
		(at 224.79 246.38 0)
		(effects
			(font
				(size 1.27 1.27)
			)
			(justify left bottom)
		)
	)
	(text "NOTE:\nremote sense"
		(exclude_from_sim no)
		(at 203.835 148.59 0)
		(effects
			(font
				(size 1.27 1.27)
			)
			(justify left bottom)
		)
	)
	(text "DIR LOW (B > A)\n"
		(exclude_from_sim no)
		(at 384.81 242.57 0)
		(effects
			(font
				(size 1.27 1.27)
			)
			(justify left bottom)
		)
	)
	(text "Set to ~1V7"
		(exclude_from_sim no)
		(at 105.41 154.94 0)
		(effects
			(font
				(size 1.27 1.27)
			)
			(justify left bottom)
		)
	)
	(text "1	2	3	4"
		(exclude_from_sim no)
		(at 25.4 185.42 0)
		(effects
			(font
				(size 1.27 1.27)
			)
			(justify left bottom)
		)
	)
	(text "+1V35"
		(exclude_from_sim no)
		(at 16.51 193.04 0)
		(effects
			(font
				(size 1.27 1.27)
			)
			(justify left bottom)
		)
	)
	(text "NOTE:\nremote sense"
		(exclude_from_sim no)
		(at 258.445 202.565 0)
		(effects
			(font
				(size 1.27 1.27)
			)
			(justify left bottom)
		)
	)
	(text "connnect sense close to FPGA"
		(exclude_from_sim no)
		(at 358.775 118.745 0)
		(effects
			(font
				(size 1.27 1.27)
			)
			(justify left bottom)
		)
	)
	(text "Soft start delay time slot"
		(exclude_from_sim no)
		(at 20.32 91.44 0)
		(effects
			(font
				(size 1.27 1.27)
			)
			(justify left bottom)
		)
	)
	(text "+5V"
		(exclude_from_sim no)
		(at 17.78 190.5 0)
		(effects
			(font
				(size 1.27 1.27)
			)
			(justify left bottom)
		)
	)
	(text "MGTAVTT Low noise LDO"
		(exclude_from_sim no)
		(at 275.59 100.965 0)
		(effects
			(font
				(size 1.27 1.27)
				(thickness 0.254)
				(bold yes)
			)
			(justify left bottom)
		)
	)
	(text "NOTE:\noptional \nexternal divider "
		(exclude_from_sim no)
		(at 227.33 151.765 0)
		(effects
			(font
				(size 1.27 1.27)
			)
			(justify left bottom)
		)
	)
	(text "X"
		(exclude_from_sim no)
		(at 33.02 104.14 0)
		(effects
			(font
				(size 1.27 1.27)
			)
			(justify left bottom)
		)
	)
	(text "Power supply sequencer"
		(exclude_from_sim no)
		(at 187.325 16.51 0)
		(effects
			(font
				(size 1.27 1.27)
				(thickness 0.254)
				(bold yes)
			)
			(justify left bottom)
		)
	)
	(text "DC-DC INT"
		(exclude_from_sim no)
		(at 275.59 16.51 0)
		(effects
			(font
				(size 1.27 1.27)
				(thickness 0.254)
				(bold yes)
			)
			(justify left bottom)
		)
	)
	(text "Load switch"
		(exclude_from_sim no)
		(at 85.725 276.86 0)
		(effects
			(font
				(size 1.27 1.27)
				(thickness 0.254)
				(bold yes)
			)
			(justify left bottom)
		)
	)
	(text "NOTE:\nremote sense"
		(exclude_from_sim no)
		(at 255.27 107.315 0)
		(effects
			(font
				(size 1.27 1.27)
			)
			(justify left bottom)
		)
	)
	(text "Dual phase"
		(exclude_from_sim no)
		(at 167.64 184.15 0)
		(effects
			(font
				(size 1.27 1.27)
			)
			(justify left bottom)
		)
	)
	(text "I2C: 0x69"
		(exclude_from_sim no)
		(at 86.995 240.665 0)
		(effects
			(font
				(size 1.27 1.27)
			)
			(justify left bottom)
		)
	)
	(text "X"
		(exclude_from_sim no)
		(at 29.845 190.5 0)
		(effects
			(font
				(size 1.27 1.27)
			)
			(justify left bottom)
		)
	)
	(text "NOTE:\nremote sense"
		(exclude_from_sim no)
		(at 258.445 240.665 0)
		(effects
			(font
				(size 1.27 1.27)
			)
			(justify left bottom)
		)
	)
	(text "NOTE:\noptional \nexternal divider "
		(exclude_from_sim no)
		(at 170.18 154.305 0)
		(effects
			(font
				(size 1.27 1.27)
			)
			(justify left bottom)
		)
	)
	(text "NOTE:\noptional \nexternal divider "
		(exclude_from_sim no)
		(at 172.72 250.825 0)
		(effects
			(font
				(size 1.27 1.27)
			)
			(justify left bottom)
		)
	)
	(text "DC-DC AUX, IO"
		(exclude_from_sim no)
		(at 13.335 83.185 0)
		(effects
			(font
				(size 1.27 1.27)
				(thickness 0.254)
				(bold yes)
			)
			(justify left bottom)
		)
	)
	(text "As both MPM54304GMN have same \naddress (from factory), there is \na need to cut SCL signals\nusing dip switch"
		(exclude_from_sim no)
		(at 22.86 239.395 0)
		(effects
			(font
				(size 1.27 1.27)
			)
			(justify left bottom)
		)
	)
	(text "+1V2"
		(exclude_from_sim no)
		(at 17.78 101.6 0)
		(effects
			(font
				(size 1.27 1.27)
			)
			(justify left bottom)
		)
	)
	(text "NOTE:\noptional \nexternal divider "
		(exclude_from_sim no)
		(at 221.615 113.03 0)
		(effects
			(font
				(size 1.27 1.27)
			)
			(justify left bottom)
		)
	)
	(text "1V2 Low noise"
		(exclude_from_sim no)
		(at 369.57 111.125 0)
		(effects
			(font
				(size 1.27 1.27)
			)
			(justify left bottom)
		)
	)
	(text "As both MPM54304GMN have same \naddress (from factory), there is \na need to cut SCL signals\nusing dip switch"
		(exclude_from_sim no)
		(at 18.415 142.24 0)
		(effects
			(font
				(size 1.27 1.27)
			)
			(justify left bottom)
		)
	)
	(text "X"
		(exclude_from_sim no)
		(at 38.1 101.6 0)
		(effects
			(font
				(size 1.27 1.27)
			)
			(justify left bottom)
		)
	)
	(text "X"
		(exclude_from_sim no)
		(at 25.2878 187.96 0)
		(effects
			(font
				(size 1.27 1.27)
			)
			(justify left bottom)
		)
	)
	(text "1	2	3	4"
		(exclude_from_sim no)
		(at 27.94 93.98 0)
		(effects
			(font
				(size 1.27 1.27)
			)
			(justify left bottom)
		)
	)
	(text "1V25"
		(exclude_from_sim no)
		(at 386.715 161.29 0)
		(effects
			(font
				(size 1.27 1.27)
			)
			(justify left bottom)
		)
	)
	(text "NOTE:\nremote sense"
		(exclude_from_sim no)
		(at 206.375 245.11 0)
		(effects
			(font
				(size 1.27 1.27)
			)
			(justify left bottom)
		)
	)
	(text "ON/OFF Button controller"
		(exclude_from_sim no)
		(at 76.2 13.97 0)
		(effects
			(font
				(size 1.27 1.27)
				(thickness 0.254)
				(bold yes)
			)
			(justify left bottom)
		)
	)
	(text "Remove R302 and mount R295 after enabling dual phase"
		(exclude_from_sim no)
		(at 165.735 282.575 0)
		(effects
			(font
				(size 1.27 1.27)
			)
			(justify left bottom)
		)
	)
	(text "NOTE:\nmount 1/2"
		(exclude_from_sim no)
		(at 72.39 59.055 0)
		(effects
			(font
				(size 1.27 1.27)
			)
			(justify left bottom)
		)
	)
	(text "+3V3"
		(exclude_from_sim no)
		(at 16.51 187.96 0)
		(effects
			(font
				(size 1.27 1.27)
			)
			(justify left bottom)
		)
	)
	(text "NOTE:\noptional \nexternal divider "
		(exclude_from_sim no)
		(at 224.79 208.28 0)
		(effects
			(font
				(size 1.27 1.27)
			)
			(justify left bottom)
		)
	)
	(text "X"
		(exclude_from_sim no)
		(at 33.02 99.06 0)
		(effects
			(font
				(size 1.27 1.27)
			)
			(justify left bottom)
		)
	)
	(text "NOTE:\noptional \nexternal divider "
		(exclude_from_sim no)
		(at 172.085 207.645 0)
		(effects
			(font
				(size 1.27 1.27)
			)
			(justify left bottom)
		)
	)
	(text "DDR3L Termination regulator"
		(exclude_from_sim no)
		(at 275.59 191.77 0)
		(effects
			(font
				(size 1.27 1.27)
				(thickness 0.254)
				(bold yes)
			)
			(justify left bottom)
		)
	)
	(text "NOTE:\nremote sense"
		(exclude_from_sim no)
		(at 205.74 201.93 0)
		(effects
			(font
				(size 1.27 1.27)
			)
			(justify left bottom)
		)
	)
	(text "NOTE2:\nwhen Res to GND mounted\n-> Alawys ON\nmount sequencer EN cap\n"
		(exclude_from_sim no)
		(at 72.39 69.85 0)
		(effects
			(font
				(size 1.27 1.27)
			)
			(justify left bottom)
		)
	)
	(junction
		(at 363.22 45.72)
		(diameter 0)
		(color 0 0 0 0)
	)
	(junction
		(at 341.63 161.29)
		(diameter 0)
		(color 0 0 0 0)
	)
	(junction
		(at 256.54 187.96)
		(diameter 0)
		(color 0 0 0 0)
	)
	(junction
		(at 341.63 45.72)
		(diameter 0)
		(color 0 0 0 0)
	)
	(junction
		(at 302.26 229.87)
		(diameter 0)
		(color 0 0 0 0)
	)
	(junction
		(at 242.57 212.09)
		(diameter 0)
		(color 0 0 0 0)
	)
	(junction
		(at 187.96 158.75)
		(diameter 0)
		(color 0 0 0 0)
	)
	(junction
		(at 379.73 45.72)
		(diameter 0)
		(color 0 0 0 0)
	)
	(junction
		(at 146.05 38.1)
		(diameter 0)
		(color 0 0 0 0)
	)
	(junction
		(at 119.38 115.57)
		(diameter 0)
		(color 0 0 0 0)
	)
	(junction
		(at 59.69 93.98)
		(diameter 0)
		(color 0 0 0 0)
	)
	(junction
		(at 146.05 269.24)
		(diameter 0)
		(color 0 0 0 0)
	)
	(junction
		(at 110.49 93.98)
		(diameter 0)
		(color 0 0 0 0)
	)
	(junction
		(at 245.11 143.51)
		(diameter 0)
		(color 0 0 0 0)
	)
	(junction
		(at 370.84 45.72)
		(diameter 0)
		(color 0 0 0 0)
	)
	(junction
		(at 350.52 121.92)
		(diameter 0)
		(color 0 0 0 0)
	)
	(junction
		(at 309.88 111.76)
		(diameter 0)
		(color 0 0 0 0)
	)
	(junction
		(at 255.27 50.8)
		(diameter 0)
		(color 0 0 0 0)
	)
	(junction
		(at 303.53 161.29)
		(diameter 0)
		(color 0 0 0 0)
	)
	(junction
		(at 146.05 45.72)
		(diameter 0)
		(color 0 0 0 0)
	)
	(junction
		(at 388.62 45.72)
		(diameter 0)
		(color 0 0 0 0)
	)
	(junction
		(at 312.42 229.87)
		(diameter 0)
		(color 0 0 0 0)
	)
	(junction
		(at 203.2 187.96)
		(diameter 0)
		(color 0 0 0 0)
	)
	(junction
		(at 204.47 231.14)
		(diameter 0)
		(color 0 0 0 0)
	)
	(junction
		(at 121.92 25.4)
		(diameter 0)
		(color 0 0 0 0)
	)
	(junction
		(at 110.49 247.65)
		(diameter 0)
		(color 0 0 0 0)
	)
	(junction
		(at 374.65 226.06)
		(diameter 0)
		(color 0 0 0 0)
	)
	(junction
		(at 121.92 17.78)
		(diameter 0)
		(color 0 0 0 0)
	)
	(junction
		(at 154.94 17.78)
		(diameter 0)
		(color 0 0 0 0)
	)
	(junction
		(at 49.53 93.98)
		(diameter 0)
		(color 0 0 0 0)
	)
	(junction
		(at 346.71 111.76)
		(diameter 0)
		(color 0 0 0 0)
	)
	(junction
		(at 265.43 53.34)
		(diameter 0)
		(color 0 0 0 0)
	)
	(junction
		(at 110.49 204.47)
		(diameter 0)
		(color 0 0 0 0)
	)
	(junction
		(at 127 259.08)
		(diameter 0)
		(color 0 0 0 0)
	)
	(junction
		(at 190.5 242.57)
		(diameter 0)
		(color 0 0 0 0)
	)
	(junction
		(at 370.84 55.88)
		(diameter 0)
		(color 0 0 0 0)
	)
	(junction
		(at 403.86 40.64)
		(diameter 0)
		(color 0 0 0 0)
	)
	(junction
		(at 403.86 233.68)
		(diameter 0)
		(color 0 0 0 0)
	)
	(junction
		(at 102.87 46.99)
		(diameter 0)
		(color 0 0 0 0)
	)
	(junction
		(at 90.17 46.99)
		(diameter 0)
		(color 0 0 0 0)
	)
	(junction
		(at 302.26 220.98)
		(diameter 0)
		(color 0 0 0 0)
	)
	(junction
		(at 153.67 35.56)
		(diameter 0)
		(color 0 0 0 0)
	)
	(junction
		(at 374.65 215.9)
		(diameter 0)
		(color 0 0 0 0)
	)
	(junction
		(at 55.88 52.07)
		(diameter 0)
		(color 0 0 0 0)
	)
	(junction
		(at 388.62 66.04)
		(diameter 0)
		(color 0 0 0 0)
	)
	(junction
		(at 364.49 226.06)
		(diameter 0)
		(color 0 0 0 0)
	)
	(junction
		(at 110.49 193.04)
		(diameter 0)
		(color 0 0 0 0)
	)
	(junction
		(at 217.17 33.02)
		(diameter 0)
		(color 0 0 0 0)
	)
	(junction
		(at 281.94 29.21)
		(diameter 0)
		(color 0 0 0 0)
	)
	(junction
		(at 303.53 177.8)
		(diameter 0)
		(color 0 0 0 0)
	)
	(junction
		(at 351.79 215.9)
		(diameter 0)
		(color 0 0 0 0)
	)
	(junction
		(at 151.13 247.65)
		(diameter 0)
		(color 0 0 0 0)
	)
	(junction
		(at 142.24 62.23)
		(diameter 0)
		(color 0 0 0 0)
	)
	(junction
		(at 190.5 255.27)
		(diameter 0)
		(color 0 0 0 0)
	)
	(junction
		(at 153.67 38.1)
		(diameter 0)
		(color 0 0 0 0)
	)
	(junction
		(at 351.79 212.09)
		(diameter 0)
		(color 0 0 0 0)
	)
	(junction
		(at 350.52 111.76)
		(diameter 0)
		(color 0 0 0 0)
	)
	(junction
		(at 118.11 38.1)
		(diameter 0)
		(color 0 0 0 0)
	)
	(junction
		(at 281.94 39.37)
		(diameter 0)
		(color 0 0 0 0)
	)
	(junction
		(at 119.38 232.41)
		(diameter 0)
		(color 0 0 0 0)
	)
	(junction
		(at 336.55 177.8)
		(diameter 0)
		(color 0 0 0 0)
	)
	(junction
		(at 110.49 104.14)
		(diameter 0)
		(color 0 0 0 0)
	)
	(junction
		(at 59.69 182.88)
		(diameter 0)
		(color 0 0 0 0)
	)
	(junction
		(at 118.11 182.88)
		(diameter 0)
		(color 0 0 0 0)
	)
	(junction
		(at 119.38 152.4)
		(diameter 0)
		(color 0 0 0 0)
	)
	(junction
		(at 110.49 115.57)
		(diameter 0)
		(color 0 0 0 0)
	)
	(junction
		(at 290.83 220.98)
		(diameter 0)
		(color 0 0 0 0)
	)
	(junction
		(at 146.05 53.34)
		(diameter 0)
		(color 0 0 0 0)
	)
	(junction
		(at 119.38 93.98)
		(diameter 0)
		(color 0 0 0 0)
	)
	(junction
		(at 110.49 182.88)
		(diameter 0)
		(color 0 0 0 0)
	)
	(junction
		(at 49.53 191.77)
		(diameter 0)
		(color 0 0 0 0)
	)
	(junction
		(at 133.35 182.88)
		(diameter 0)
		(color 0 0 0 0)
	)
	(junction
		(at 252.73 93.98)
		(diameter 0)
		(color 0 0 0 0)
	)
	(junction
		(at 200.66 93.98)
		(diameter 0)
		(color 0 0 0 0)
	)
	(junction
		(at 49.53 102.87)
		(diameter 0)
		(color 0 0 0 0)
	)
	(junction
		(at 187.96 146.05)
		(diameter 0)
		(color 0 0 0 0)
	)
	(junction
		(at 176.53 242.57)
		(diameter 0)
		(color 0 0 0 0)
	)
	(junction
		(at 68.58 143.51)
		(diameter 0)
		(color 0 0 0 0)
	)
	(junction
		(at 293.37 29.21)
		(diameter 0)
		(color 0 0 0 0)
	)
	(junction
		(at 306.07 29.21)
		(diameter 0)
		(color 0 0 0 0)
	)
	(junction
		(at 337.82 237.49)
		(diameter 0)
		(color 0 0 0 0)
	)
	(junction
		(at 232.41 33.02)
		(diameter 0)
		(color 0 0 0 0)
	)
	(junction
		(at 119.38 125.73)
		(diameter 0)
		(color 0 0 0 0)
	)
	(junction
		(at 355.6 236.22)
		(diameter 0)
		(color 0 0 0 0)
	)
	(junction
		(at 186.69 105.41)
		(diameter 0)
		(color 0 0 0 0)
	)
	(junction
		(at 119.38 182.88)
		(diameter 0)
		(color 0 0 0 0)
	)
	(junction
		(at 49.53 201.93)
		(diameter 0)
		(color 0 0 0 0)
	)
	(junction
		(at 312.42 196.85)
		(diameter 0)
		(color 0 0 0 0)
	)
	(junction
		(at 311.15 161.29)
		(diameter 0)
		(color 0 0 0 0)
	)
	(junction
		(at 363.22 55.88)
		(diameter 0)
		(color 0 0 0 0)
	)
	(junction
		(at 242.57 250.19)
		(diameter 0)
		(color 0 0 0 0)
	)
	(junction
		(at 119.38 143.51)
		(diameter 0)
		(color 0 0 0 0)
	)
	(junction
		(at 290.83 229.87)
		(diameter 0)
		(color 0 0 0 0)
	)
	(junction
		(at 323.85 177.8)
		(diameter 0)
		(color 0 0 0 0)
	)
	(junction
		(at 377.19 172.72)
		(diameter 0)
		(color 0 0 0 0)
	)
	(junction
		(at 55.88 39.37)
		(diameter 0)
		(color 0 0 0 0)
	)
	(junction
		(at 242.57 238.76)
		(diameter 0)
		(color 0 0 0 0)
	)
	(junction
		(at 71.12 218.44)
		(diameter 0)
		(color 0 0 0 0)
	)
	(junction
		(at 119.38 222.25)
		(diameter 0)
		(color 0 0 0 0)
	)
	(junction
		(at 71.12 132.08)
		(diameter 0)
		(color 0 0 0 0)
	)
	(junction
		(at 119.38 214.63)
		(diameter 0)
		(color 0 0 0 0)
	)
	(junction
		(at 355.6 215.9)
		(diameter 0)
		(color 0 0 0 0)
	)
	(junction
		(at 186.69 116.84)
		(diameter 0)
		(color 0 0 0 0)
	)
	(junction
		(at 151.13 259.08)
		(diameter 0)
		(color 0 0 0 0)
	)
	(junction
		(at 71.12 129.54)
		(diameter 0)
		(color 0 0 0 0)
	)
	(junction
		(at 119.38 104.14)
		(diameter 0)
		(color 0 0 0 0)
	)
	(junction
		(at 309.88 127)
		(diameter 0)
		(color 0 0 0 0)
	)
	(junction
		(at 118.11 62.23)
		(diameter 0)
		(color 0 0 0 0)
	)
	(junction
		(at 64.77 229.87)
		(diameter 0)
		(color 0 0 0 0)
	)
	(junction
		(at 377.19 161.29)
		(diameter 0)
		(color 0 0 0 0)
	)
	(junction
		(at 213.36 50.8)
		(diameter 0)
		(color 0 0 0 0)
	)
	(junction
		(at 189.23 199.39)
		(diameter 0)
		(color 0 0 0 0)
	)
	(junction
		(at 119.38 133.35)
		(diameter 0)
		(color 0 0 0 0)
	)
	(junction
		(at 388.62 54.61)
		(diameter 0)
		(color 0 0 0 0)
	)
	(junction
		(at 238.76 105.41)
		(diameter 0)
		(color 0 0 0 0)
	)
	(junction
		(at 25.4 39.37)
		(diameter 0)
		(color 0 0 0 0)
	)
	(junction
		(at 245.11 48.26)
		(diameter 0)
		(color 0 0 0 0)
	)
	(junction
		(at 119.38 40.64)
		(diameter 0)
		(color 0 0 0 0)
	)
	(junction
		(at 118.11 93.98)
		(diameter 0)
		(color 0 0 0 0)
	)
	(junction
		(at 71.12 220.98)
		(diameter 0)
		(color 0 0 0 0)
	)
	(junction
		(at 21.59 39.37)
		(diameter 0)
		(color 0 0 0 0)
	)
	(junction
		(at 127 247.65)
		(diameter 0)
		(color 0 0 0 0)
	)
	(junction
		(at 312.42 238.76)
		(diameter 0)
		(color 0 0 0 0)
	)
	(junction
		(at 68.58 140.97)
		(diameter 0)
		(color 0 0 0 0)
	)
	(junction
		(at 119.38 193.04)
		(diameter 0)
		(color 0 0 0 0)
	)
	(junction
		(at 238.76 116.84)
		(diameter 0)
		(color 0 0 0 0)
	)
	(junction
		(at 242.57 200.66)
		(diameter 0)
		(color 0 0 0 0)
	)
	(junction
		(at 328.93 77.47)
		(diameter 0)
		(color 0 0 0 0)
	)
	(junction
		(at 245.11 33.02)
		(diameter 0)
		(color 0 0 0 0)
	)
	(junction
		(at 255.27 33.02)
		(diameter 0)
		(color 0 0 0 0)
	)
	(junction
		(at 330.2 111.76)
		(diameter 0)
		(color 0 0 0 0)
	)
	(junction
		(at 119.38 204.47)
		(diameter 0)
		(color 0 0 0 0)
	)
	(junction
		(at 293.37 39.37)
		(diameter 0)
		(color 0 0 0 0)
	)
	(junction
		(at 281.94 220.98)
		(diameter 0)
		(color 0 0 0 0)
	)
	(junction
		(at 364.49 215.9)
		(diameter 0)
		(color 0 0 0 0)
	)
	(junction
		(at 189.23 212.09)
		(diameter 0)
		(color 0 0 0 0)
	)
	(junction
		(at 354.33 45.72)
		(diameter 0)
		(color 0 0 0 0)
	)
	(junction
		(at 256.54 226.06)
		(diameter 0)
		(color 0 0 0 0)
	)
	(junction
		(at 49.53 182.88)
		(diameter 0)
		(color 0 0 0 0)
	)
	(junction
		(at 379.73 55.88)
		(diameter 0)
		(color 0 0 0 0)
	)
	(junction
		(at 201.93 134.62)
		(diameter 0)
		(color 0 0 0 0)
	)
	(junction
		(at 290.83 161.29)
		(diameter 0)
		(color 0 0 0 0)
	)
	(no_connect
		(at 99.06 125.73)
	)
	(no_connect
		(at 99.06 113.03)
	)
	(bus_entry
		(at 303.53 64.77)
		(size 1.27 -1.27)
		(stroke
			(width 0)
			(type default)
		)
	)
	(bus_entry
		(at 303.53 67.31)
		(size 1.27 -1.27)
		(stroke
			(width 0)
			(type default)
		)
	)
	(bus_entry
		(at 33.02 220.98)
		(size -1.27 -1.27)
		(stroke
			(width 0)
			(type default)
		)
	)
	(bus_entry
		(at 92.71 38.1)
		(size 1.27 0)
		(stroke
			(width 0)
			(type default)
		)
	)
	(bus_entry
		(at 44.45 251.46)
		(size 1.27 -1.27)
		(stroke
			(width 0)
			(type default)
		)
	)
	(bus_entry
		(at 49.53 142.24)
		(size 1.27 -1.27)
		(stroke
			(width 0)
			(type default)
		)
	)
	(bus_entry
		(at 16.51 128.27)
		(size 1.27 1.27)
		(stroke
			(width 0)
			(type default)
		)
	)
	(bus_entry
		(at 31.75 217.17)
		(size 1.27 1.27)
		(stroke
			(width 0)
			(type default)
		)
	)
	(bus_entry
		(at 299.72 60.96)
		(size 1.27 -1.27)
		(stroke
			(width 0)
			(type default)
		)
	)
	(bus_entry
		(at 107.95 273.05)
		(size 1.27 0)
		(stroke
			(width 0)
			(type default)
		)
	)
	(bus_entry
		(at 49.53 144.78)
		(size 1.27 -1.27)
		(stroke
			(width 0)
			(type default)
		)
	)
	(bus_entry
		(at 93.98 35.56)
		(size 1.27 0)
		(stroke
			(width 0)
			(type default)
		)
	)
	(bus_entry
		(at 17.78 132.08)
		(size -1.27 -1.27)
		(stroke
			(width 0)
			(type default)
		)
	)
	(bus_entry
		(at 121.92 46.99)
		(size 1.27 -1.27)
		(stroke
			(width 0)
			(type default)
		)
	)
	(wire
		(pts
			(xy 99.06 212.09) (xy 106.68 212.09)
		)
		(stroke
			(width 0)
			(type default)
		)
	)
	(wire
		(pts
			(xy 351.79 199.39) (xy 351.79 203.2)
		)
		(stroke
			(width 0)
			(type default)
		)
	)
	(wire
		(pts
			(xy 99.06 207.01) (xy 105.41 207.01)
		)
		(stroke
			(width 0)
			(type default)
		)
	)
	(polyline
		(pts
			(xy 196.85 114.3) (xy 168.91 114.3)
		)
		(stroke
			(width 0)
			(type default)
		)
	)
	(wire
		(pts
			(xy 142.24 71.12) (xy 142.24 72.39)
		)
		(stroke
			(width 0)
			(type default)
		)
	)
	(wire
		(pts
			(xy 119.38 214.63) (xy 119.38 215.9)
		)
		(stroke
			(width 0)
			(type default)
		)
	)
	(polyline
		(pts
			(xy 85.09 280.67) (xy 85.09 267.97)
		)
		(stroke
			(width 0)
			(type default)
		)
	)
	(polyline
		(pts
			(xy 251.46 201.93) (xy 251.46 209.55)
		)
		(stroke
			(width 0)
			(type default)
		)
	)
	(wire
		(pts
			(xy 314.96 68.58) (xy 318.77 68.58)
		)
		(stroke
			(width 0)
			(type default)
		)
	)
	(wire
		(pts
			(xy 69.85 182.88) (xy 69.85 199.39)
		)
		(stroke
			(width 0)
			(type default)
		)
	)
	(polyline
		(pts
			(xy 407.67 187.96) (xy 274.32 187.96)
		)
		(stroke
			(width 0)
			(type default)
		)
	)
	(wire
		(pts
			(xy 213.36 50.8) (xy 222.25 50.8)
		)
		(stroke
			(width 0)
			(type default)
		)
	)
	(wire
		(pts
			(xy 293.37 36.83) (xy 293.37 39.37)
		)
		(stroke
			(width 0)
			(type default)
		)
	)
	(polyline
		(pts
			(xy 16.51 99.06) (xy 16.51 104.14)
		)
		(stroke
			(width 0)
			(type default)
		)
	)
	(wire
		(pts
			(xy 290.83 161.29) (xy 294.64 161.29)
		)
		(stroke
			(width 0)
			(type default)
		)
	)
	(wire
		(pts
			(xy 328.93 77.47) (xy 330.2 77.47)
		)
		(stroke
			(width 0)
			(type default)
		)
	)
	(wire
		(pts
			(xy 99.06 143.51) (xy 110.49 143.51)
		)
		(stroke
			(width 0)
			(type default)
		)
	)
	(wire
		(pts
			(xy 160.02 39.37) (xy 160.02 62.23)
		)
		(stroke
			(width 0)
			(type default)
		)
	)
	(wire
		(pts
			(xy 281.94 29.21) (xy 281.94 31.75)
		)
		(stroke
			(width 0)
			(type default)
		)
	)
	(polyline
		(pts
			(xy 16.51 101.6) (xy 45.72 101.6)
		)
		(stroke
			(width 0)
			(type default)
		)
	)
	(wire
		(pts
			(xy 242.57 250.19) (xy 256.54 250.19)
		)
		(stroke
			(width 0)
			(type default)
		)
	)
	(wire
		(pts
			(xy 203.2 187.96) (xy 219.71 187.96)
		)
		(stroke
			(width 0)
			(type default)
		)
	)
	(wire
		(pts
			(xy 133.35 220.98) (xy 133.35 222.25)
		)
		(stroke
			(width 0)
			(type default)
		)
	)
	(wire
		(pts
			(xy 328.93 31.75) (xy 332.74 31.75)
		)
		(stroke
			(width 0)
			(type default)
		)
	)
	(wire
		(pts
			(xy 187.96 153.67) (xy 187.96 158.75)
		)
		(stroke
			(width 0)
			(type default)
		)
	)
	(wire
		(pts
			(xy 377.19 161.29) (xy 379.73 161.29)
		)
		(stroke
			(width 0)
			(type default)
		)
	)
	(wire
		(pts
			(xy 106.68 212.09) (xy 106.68 204.47)
		)
		(stroke
			(width 0)
			(type default)
		)
	)
	(wire
		(pts
			(xy 397.51 45.72) (xy 403.86 45.72)
		)
		(stroke
			(width 0)
			(type default)
		)
	)
	(wire
		(pts
			(xy 354.33 53.34) (xy 354.33 55.88)
		)
		(stroke
			(width 0)
			(type default)
		)
	)
	(wire
		(pts
			(xy 190.5 255.27) (xy 207.01 255.27)
		)
		(stroke
			(width 0)
			(type default)
		)
	)
	(wire
		(pts
			(xy 302.26 229.87) (xy 302.26 232.41)
		)
		(stroke
			(width 0)
			(type default)
		)
	)
	(wire
		(pts
			(xy 335.28 237.49) (xy 337.82 237.49)
		)
		(stroke
			(width 0)
			(type default)
		)
	)
	(wire
		(pts
			(xy 59.69 191.77) (xy 49.53 191.77)
		)
		(stroke
			(width 0)
			(type default)
		)
	)
	(wire
		(pts
			(xy 187.96 158.75) (xy 203.2 158.75)
		)
		(stroke
			(width 0)
			(type default)
		)
	)
	(wire
		(pts
			(xy 281.94 228.6) (xy 281.94 229.87)
		)
		(stroke
			(width 0)
			(type default)
		)
	)
	(wire
		(pts
			(xy 238.76 102.87) (xy 238.76 105.41)
		)
		(stroke
			(width 0)
			(type default)
		)
	)
	(wire
		(pts
			(xy 118.11 35.56) (xy 118.11 38.1)
		)
		(stroke
			(width 0)
			(type default)
		)
	)
	(polyline
		(pts
			(xy 273.05 241.3) (xy 254 241.3)
		)
		(stroke
			(width 0)
			(type default)
		)
	)
	(wire
		(pts
			(xy 256.54 181.61) (xy 256.54 182.88)
		)
		(stroke
			(width 0)
			(type default)
		)
	)
	(wire
		(pts
			(xy 232.41 33.02) (xy 232.41 43.18)
		)
		(stroke
			(width 0)
			(type default)
		)
	)
	(bus
		(pts
			(xy 16.51 128.27) (xy 16.51 123.19)
		)
		(stroke
			(width 0)
			(type default)
		)
	)
	(wire
		(pts
			(xy 119.38 104.14) (xy 119.38 105.41)
		)
		(stroke
			(width 0)
			(type default)
		)
	)
	(polyline
		(pts
			(xy 16.51 96.52) (xy 45.72 96.52)
		)
		(stroke
			(width 0)
			(type default)
		)
	)
	(wire
		(pts
			(xy 106.68 204.47) (xy 110.49 204.47)
		)
		(stroke
			(width 0)
			(type default)
		)
	)
	(wire
		(pts
			(xy 345.44 116.84) (xy 346.71 116.84)
		)
		(stroke
			(width 0)
			(type default)
		)
	)
	(wire
		(pts
			(xy 312.42 229.87) (xy 325.12 229.87)
		)
		(stroke
			(width 0)
			(type default)
		)
	)
	(wire
		(pts
			(xy 119.38 133.35) (xy 119.38 135.89)
		)
		(stroke
			(width 0)
			(type default)
		)
	)
	(wire
		(pts
			(xy 401.32 214.63) (xy 401.32 217.17)
		)
		(stroke
			(width 0)
			(type default)
		)
	)
	(wire
		(pts
			(xy 102.87 234.95) (xy 99.06 234.95)
		)
		(stroke
			(width 0)
			(type default)
		)
	)
	(wire
		(pts
			(xy 403.86 36.83) (xy 403.86 40.64)
		)
		(stroke
			(width 0)
			(type default)
		)
	)
	(wire
		(pts
			(xy 153.67 35.56) (xy 161.29 35.56)
		)
		(stroke
			(width 0)
			(type default)
		)
	)
	(polyline
		(pts
			(xy 199.39 243.84) (xy 199.39 252.73)
		)
		(stroke
			(width 0)
			(type default)
		)
	)
	(polyline
		(pts
			(xy 222.25 280.67) (xy 166.37 280.67)
		)
		(stroke
			(width 0)
			(type default)
		)
	)
	(polyline
		(pts
			(xy 45.72 104.14) (xy 45.72 99.06)
		)
		(stroke
			(width 0)
			(type default)
		)
	)
	(wire
		(pts
			(xy 69.85 234.95) (xy 71.12 234.95)
		)
		(stroke
			(width 0)
			(type default)
		)
	)
	(wire
		(pts
			(xy 99.06 214.63) (xy 102.87 214.63)
		)
		(stroke
			(width 0)
			(type default)
		)
	)
	(wire
		(pts
			(xy 71.12 146.05) (xy 69.85 146.05)
		)
		(stroke
			(width 0)
			(type default)
		)
	)
	(wire
		(pts
			(xy 336.55 177.8) (xy 323.85 177.8)
		)
		(stroke
			(width 0)
			(type default)
		)
	)
	(wire
		(pts
			(xy 393.7 207.01) (xy 393.7 209.55)
		)
		(stroke
			(width 0)
			(type default)
		)
	)
	(wire
		(pts
			(xy 110.49 123.19) (xy 110.49 125.73)
		)
		(stroke
			(width 0)
			(type default)
		)
	)
	(wire
		(pts
			(xy 21.59 39.37) (xy 21.59 45.72)
		)
		(stroke
			(width 0)
			(type default)
		)
	)
	(wire
		(pts
			(xy 388.62 40.64) (xy 392.43 40.64)
		)
		(stroke
			(width 0)
			(type default)
		)
	)
	(wire
		(pts
			(xy 67.31 120.65) (xy 71.12 120.65)
		)
		(stroke
			(width 0)
			(type default)
		)
	)
	(wire
		(pts
			(xy 363.22 55.88) (xy 370.84 55.88)
		)
		(stroke
			(width 0)
			(type default)
		)
	)
	(wire
		(pts
			(xy 383.54 215.9) (xy 386.08 215.9)
		)
		(stroke
			(width 0)
			(type default)
		)
	)
	(wire
		(pts
			(xy 341.63 161.29) (xy 355.6 161.29)
		)
		(stroke
			(width 0)
			(type default)
		)
	)
	(wire
		(pts
			(xy 346.71 121.92) (xy 350.52 121.92)
		)
		(stroke
			(width 0)
			(type default)
		)
	)
	(wire
		(pts
			(xy 118.11 182.88) (xy 119.38 182.88)
		)
		(stroke
			(width 0)
			(type default)
		)
	)
	(polyline
		(pts
			(xy 254 190.5) (xy 254 203.2)
		)
		(stroke
			(width 0)
			(type default)
		)
	)
	(wire
		(pts
			(xy 317.5 116.84) (xy 317.5 119.38)
		)
		(stroke
			(width 0)
			(type default)
		)
	)
	(wire
		(pts
			(xy 373.38 66.04) (xy 388.62 66.04)
		)
		(stroke
			(width 0)
			(type default)
		)
	)
	(polyline
		(pts
			(xy 218.44 149.86) (xy 199.39 149.86)
		)
		(stroke
			(width 0)
			(type default)
		)
	)
	(wire
		(pts
			(xy 328.93 77.47) (xy 328.93 78.74)
		)
		(stroke
			(width 0)
			(type default)
		)
	)
	(wire
		(pts
			(xy 340.36 234.95) (xy 340.36 237.49)
		)
		(stroke
			(width 0)
			(type default)
		)
	)
	(wire
		(pts
			(xy 330.2 116.84) (xy 317.5 116.84)
		)
		(stroke
			(width 0)
			(type default)
		)
	)
	(polyline
		(pts
			(xy 222.25 66.04) (xy 189.23 66.04)
		)
		(stroke
			(width 0)
			(type default)
		)
	)
	(wire
		(pts
			(xy 102.87 217.17) (xy 99.06 217.17)
		)
		(stroke
			(width 0)
			(type default)
		)
	)
	(wire
		(pts
			(xy 180.34 189.23) (xy 189.23 189.23)
		)
		(stroke
			(width 0)
			(type default)
		)
	)
	(wire
		(pts
			(xy 187.96 146.05) (xy 187.96 148.59)
		)
		(stroke
			(width 0)
			(type default)
		)
	)
	(wire
		(pts
			(xy 245.11 33.02) (xy 245.11 39.37)
		)
		(stroke
			(width 0)
			(type default)
		)
	)
	(wire
		(pts
			(xy 281.94 229.87) (xy 290.83 229.87)
		)
		(stroke
			(width 0)
			(type default)
		)
	)
	(wire
		(pts
			(xy 345.44 114.3) (xy 346.71 114.3)
		)
		(stroke
			(width 0)
			(type default)
		)
	)
	(wire
		(pts
			(xy 336.55 166.37) (xy 336.55 177.8)
		)
		(stroke
			(width 0)
			(type default)
		)
	)
	(wire
		(pts
			(xy 55.88 53.34) (xy 55.88 52.07)
		)
		(stroke
			(width 0)
			(type default)
		)
	)
	(wire
		(pts
			(xy 330.2 73.66) (xy 330.2 77.47)
		)
		(stroke
			(width 0)
			(type default)
		)
	)
	(wire
		(pts
			(xy 379.73 55.88) (xy 379.73 57.15)
		)
		(stroke
			(width 0)
			(type default)
		)
	)
	(wire
		(pts
			(xy 121.92 269.24) (xy 146.05 269.24)
		)
		(stroke
			(width 0)
			(type default)
		)
	)
	(polyline
		(pts
			(xy 19.05 171.45) (xy 266.7 171.45)
		)
		(stroke
			(width 0)
			(type dot)
		)
	)
	(wire
		(pts
			(xy 127 259.08) (xy 129.54 259.08)
		)
		(stroke
			(width 0)
			(type default)
		)
	)
	(polyline
		(pts
			(xy 274.32 96.52) (xy 274.32 138.43)
		)
		(stroke
			(width 0)
			(type default)
		)
	)
	(wire
		(pts
			(xy 290.83 220.98) (xy 290.83 223.52)
		)
		(stroke
			(width 0)
			(type default)
		)
	)
	(wire
		(pts
			(xy 186.69 93.98) (xy 186.69 97.79)
		)
		(stroke
			(width 0)
			(type default)
		)
	)
	(bus
		(pts
			(xy 303.53 67.31) (xy 303.53 76.2)
		)
		(stroke
			(width 0)
			(type default)
		)
	)
	(wire
		(pts
			(xy 332.74 166.37) (xy 336.55 166.37)
		)
		(stroke
			(width 0)
			(type default)
		)
	)
	(polyline
		(pts
			(xy 254 228.6) (xy 273.05 228.6)
		)
		(stroke
			(width 0)
			(type default)
		)
	)
	(wire
		(pts
			(xy 157.48 17.78) (xy 154.94 17.78)
		)
		(stroke
			(width 0)
			(type default)
		)
	)
	(wire
		(pts
			(xy 302.26 220.98) (xy 325.12 220.98)
		)
		(stroke
			(width 0)
			(type default)
		)
	)
	(wire
		(pts
			(xy 186.69 105.41) (xy 186.69 107.95)
		)
		(stroke
			(width 0)
			(type default)
		)
	)
	(wire
		(pts
			(xy 25.4 228.6) (xy 25.4 229.87)
		)
		(stroke
			(width 0)
			(type default)
		)
	)
	(bus
		(pts
			(xy 44.45 252.73) (xy 44.45 251.46)
		)
		(stroke
			(width 0)
			(type default)
		)
	)
	(wire
		(pts
			(xy 232.41 33.02) (xy 245.11 33.02)
		)
		(stroke
			(width 0)
			(type default)
		)
	)
	(polyline
		(pts
			(xy 407.67 96.52) (xy 274.32 96.52)
		)
		(stroke
			(width 0)
			(type default)
		)
	)
	(wire
		(pts
			(xy 118.11 93.98) (xy 119.38 93.98)
		)
		(stroke
			(width 0)
			(type default)
		)
	)
	(wire
		(pts
			(xy 110.49 104.14) (xy 119.38 104.14)
		)
		(stroke
			(width 0)
			(type default)
		)
	)
	(wire
		(pts
			(xy 256.54 226.06) (xy 256.54 231.14)
		)
		(stroke
			(width 0)
			(type default)
		)
	)
	(polyline
		(pts
			(xy 199.39 252.73) (xy 172.72 252.73)
		)
		(stroke
			(width 0)
			(type default)
		)
	)
	(wire
		(pts
			(xy 233.68 189.23) (xy 242.57 189.23)
		)
		(stroke
			(width 0)
			(type default)
		)
	)
	(bus
		(pts
			(xy 49.53 146.05) (xy 48.26 147.32)
		)
		(stroke
			(width 0)
			(type default)
		)
	)
	(wire
		(pts
			(xy 181.61 146.05) (xy 187.96 146.05)
		)
		(stroke
			(width 0)
			(type default)
		)
	)
	(wire
		(pts
			(xy 327.66 77.47) (xy 328.93 77.47)
		)
		(stroke
			(width 0)
			(type default)
		)
	)
	(wire
		(pts
			(xy 119.38 182.88) (xy 124.46 182.88)
		)
		(stroke
			(width 0)
			(type default)
		)
	)
	(wire
		(pts
			(xy 100.33 93.98) (xy 110.49 93.98)
		)
		(stroke
			(width 0)
			(type default)
		)
	)
	(wire
		(pts
			(xy 242.57 50.8) (xy 255.27 50.8)
		)
		(stroke
			(width 0)
			(type default)
		)
	)
	(polyline
		(pts
			(xy 35.56 91.44) (xy 35.56 104.14)
		)
		(stroke
			(width 0)
			(type default)
		)
	)
	(wire
		(pts
			(xy 312.42 50.8) (xy 318.77 50.8)
		)
		(stroke
			(width 0)
			(type default)
		)
	)
	(wire
		(pts
			(xy 33.02 220.98) (xy 71.12 220.98)
		)
		(stroke
			(width 0)
			(type default)
		)
	)
	(wire
		(pts
			(xy 49.53 120.65) (xy 49.53 121.92)
		)
		(stroke
			(width 0)
			(type default)
		)
	)
	(wire
		(pts
			(xy 119.38 229.87) (xy 119.38 232.41)
		)
		(stroke
			(width 0)
			(type default)
		)
	)
	(wire
		(pts
			(xy 312.42 238.76) (xy 312.42 240.03)
		)
		(stroke
			(width 0)
			(type default)
		)
	)
	(wire
		(pts
			(xy 128.27 264.16) (xy 128.27 273.05)
		)
		(stroke
			(width 0)
			(type default)
		)
	)
	(wire
		(pts
			(xy 189.23 217.17) (xy 189.23 218.44)
		)
		(stroke
			(width 0)
			(type default)
		)
	)
	(wire
		(pts
			(xy 119.38 212.09) (xy 119.38 214.63)
		)
		(stroke
			(width 0)
			(type default)
		)
	)
	(wire
		(pts
			(xy 114.3 232.41) (xy 119.38 232.41)
		)
		(stroke
			(width 0)
			(type default)
		)
	)
	(wire
		(pts
			(xy 290.83 171.45) (xy 290.83 177.8)
		)
		(stroke
			(width 0)
			(type default)
		)
	)
	(polyline
		(pts
			(xy 38.1 182.88) (xy 38.1 193.04)
		)
		(stroke
			(width 0)
			(type default)
		)
	)
	(wire
		(pts
			(xy 306.07 36.83) (xy 306.07 39.37)
		)
		(stroke
			(width 0)
			(type default)
		)
	)
	(wire
		(pts
			(xy 49.53 93.98) (xy 49.53 95.25)
		)
		(stroke
			(width 0)
			(type default)
		)
	)
	(polyline
		(pts
			(xy 407.67 139.7) (xy 274.32 139.7)
		)
		(stroke
			(width 0)
			(type default)
		)
	)
	(wire
		(pts
			(xy 377.19 161.29) (xy 377.19 165.1)
		)
		(stroke
			(width 0)
			(type default)
		)
	)
	(wire
		(pts
			(xy 119.38 123.19) (xy 119.38 125.73)
		)
		(stroke
			(width 0)
			(type default)
		)
	)
	(wire
		(pts
			(xy 337.82 234.95) (xy 337.82 237.49)
		)
		(stroke
			(width 0)
			(type default)
		)
	)
	(wire
		(pts
			(xy 88.9 62.23) (xy 105.41 62.23)
		)
		(stroke
			(width 0)
			(type default)
		)
	)
	(wire
		(pts
			(xy 386.08 238.76) (xy 384.81 238.76)
		)
		(stroke
			(width 0)
			(type default)
		)
	)
	(wire
		(pts
			(xy 354.33 45.72) (xy 354.33 48.26)
		)
		(stroke
			(width 0)
			(type default)
		)
	)
	(wire
		(pts
			(xy 160.02 39.37) (xy 161.29 39.37)
		)
		(stroke
			(width 0)
			(type default)
		)
	)
	(wire
		(pts
			(xy 337.82 237.49) (xy 340.36 237.49)
		)
		(stroke
			(width 0)
			(type default)
		)
	)
	(wire
		(pts
			(xy 302.26 238.76) (xy 312.42 238.76)
		)
		(stroke
			(width 0)
			(type default)
		)
	)
	(bus
		(pts
			(xy 31.75 215.9) (xy 33.02 214.63)
		)
		(stroke
			(width 0)
			(type default)
		)
	)
	(polyline
		(pts
			(xy 45.72 96.52) (xy 45.72 88.9)
		)
		(stroke
			(width 0)
			(type default)
		)
	)
	(wire
		(pts
			(xy 323.85 173.99) (xy 323.85 177.8)
		)
		(stroke
			(width 0)
			(type default)
		)
	)
	(wire
		(pts
			(xy 49.53 201.93) (xy 49.53 204.47)
		)
		(stroke
			(width 0)
			(type default)
		)
	)
	(wire
		(pts
			(xy 364.49 215.9) (xy 364.49 218.44)
		)
		(stroke
			(width 0)
			(type default)
		)
	)
	(wire
		(pts
			(xy 255.27 44.45) (xy 255.27 50.8)
		)
		(stroke
			(width 0)
			(type default)
		)
	)
	(wire
		(pts
			(xy 119.38 190.5) (xy 119.38 193.04)
		)
		(stroke
			(width 0)
			(type default)
		)
	)
	(polyline
		(pts
			(xy 170.18 147.32) (xy 170.18 156.21)
		)
		(stroke
			(width 0)
			(type default)
		)
	)
	(wire
		(pts
			(xy 256.54 186.69) (xy 256.54 187.96)
		)
		(stroke
			(width 0)
			(type default)
		)
	)
	(polyline
		(pts
			(xy 170.18 147.32) (xy 196.85 147.32)
		)
		(stroke
			(width 0)
			(type default)
		)
	)
	(wire
		(pts
			(xy 190.5 229.87) (xy 190.5 234.95)
		)
		(stroke
			(width 0)
			(type default)
		)
	)
	(polyline
		(pts
			(xy 220.98 106.68) (xy 248.92 106.68)
		)
		(stroke
			(width 0)
			(type default)
		)
	)
	(wire
		(pts
			(xy 99.06 232.41) (xy 106.68 232.41)
		)
		(stroke
			(width 0)
			(type default)
		)
	)
	(wire
		(pts
			(xy 190.5 250.19) (xy 190.5 255.27)
		)
		(stroke
			(width 0)
			(type default)
		)
	)
	(wire
		(pts
			(xy 49.53 182.88) (xy 59.69 182.88)
		)
		(stroke
			(width 0)
			(type default)
		)
	)
	(wire
		(pts
			(xy 153.67 52.07) (xy 153.67 53.34)
		)
		(stroke
			(width 0)
			(type default)
		)
	)
	(wire
		(pts
			(xy 350.52 111.76) (xy 350.52 115.57)
		)
		(stroke
			(width 0)
			(type default)
		)
	)
	(wire
		(pts
			(xy 245.11 143.51) (xy 245.11 146.05)
		)
		(stroke
			(width 0)
			(type default)
		)
	)
	(wire
		(pts
			(xy 350.52 76.2) (xy 350.52 78.74)
		)
		(stroke
			(width 0)
			(type default)
		)
	)
	(polyline
		(pts
			(xy 217.17 107.95) (xy 199.39 107.95)
		)
		(stroke
			(width 0)
			(type default)
		)
	)
	(wire
		(pts
			(xy 118.11 62.23) (xy 142.24 62.23)
		)
		(stroke
			(width 0)
			(type default)
		)
	)
	(wire
		(pts
			(xy 106.68 247.65) (xy 110.49 247.65)
		)
		(stroke
			(width 0)
			(type default)
		)
	)
	(polyline
		(pts
			(xy 172.72 243.84) (xy 199.39 243.84)
		)
		(stroke
			(width 0)
			(type default)
		)
	)
	(wire
		(pts
			(xy 105.41 104.14) (xy 110.49 104.14)
		)
		(stroke
			(width 0)
			(type default)
		)
	)
	(wire
		(pts
			(xy 129.54 264.16) (xy 128.27 264.16)
		)
		(stroke
			(width 0)
			(type default)
		)
	)
	(wire
		(pts
			(xy 189.23 50.8) (xy 194.31 50.8)
		)
		(stroke
			(width 0)
			(type default)
		)
	)
	(wire
		(pts
			(xy 59.69 182.88) (xy 69.85 182.88)
		)
		(stroke
			(width 0)
			(type default)
		)
	)
	(polyline
		(pts
			(xy 224.79 240.03) (xy 224.79 247.65)
		)
		(stroke
			(width 0)
			(type default)
		)
	)
	(wire
		(pts
			(xy 281.94 39.37) (xy 281.94 40.64)
		)
		(stroke
			(width 0)
			(type default)
		)
	)
	(polyline
		(pts
			(xy 251.46 209.55) (xy 224.79 209.55)
		)
		(stroke
			(width 0)
			(type default)
		)
	)
	(polyline
		(pts
			(xy 72.39 54.61) (xy 120.65 54.61)
		)
		(stroke
			(width 0)
			(type default)
		)
	)
	(bus
		(pts
			(xy 297.18 77.47) (xy 302.26 77.47)
		)
		(stroke
			(width 0)
			(type default)
		)
	)
	(wire
		(pts
			(xy 314.96 29.21) (xy 314.96 45.72)
		)
		(stroke
			(width 0)
			(type default)
		)
	)
	(wire
		(pts
			(xy 68.58 140.97) (xy 68.58 143.51)
		)
		(stroke
			(width 0)
			(type default)
		)
	)
	(wire
		(pts
			(xy 25.4 229.87) (xy 64.77 229.87)
		)
		(stroke
			(width 0)
			(type default)
		)
	)
	(wire
		(pts
			(xy 350.52 45.72) (xy 354.33 45.72)
		)
		(stroke
			(width 0)
			(type default)
		)
	)
	(polyline
		(pts
			(xy 227.33 144.78) (xy 227.33 153.67)
		)
		(stroke
			(width 0)
			(type default)
		)
	)
	(wire
		(pts
			(xy 350.52 120.65) (xy 350.52 121.92)
		)
		(stroke
			(width 0)
			(type default)
		)
	)
	(wire
		(pts
			(xy 59.69 182.88) (xy 59.69 184.15)
		)
		(stroke
			(width 0)
			(type default)
		)
	)
	(wire
		(pts
			(xy 100.33 182.88) (xy 110.49 182.88)
		)
		(stroke
			(width 0)
			(type default)
		)
	)
	(wire
		(pts
			(xy 119.38 33.02) (xy 119.38 40.64)
		)
		(stroke
			(width 0)
			(type default)
		)
	)
	(polyline
		(pts
			(xy 16.51 185.42) (xy 43.18 185.42)
		)
		(stroke
			(width 0)
			(type default)
		)
	)
	(bus
		(pts
			(xy 24.13 121.92) (xy 17.78 121.92)
		)
		(stroke
			(width 0)
			(type default)
		)
	)
	(wire
		(pts
			(xy 252.73 102.87) (xy 252.73 105.41)
		)
		(stroke
			(width 0)
			(type default)
		)
	)
	(wire
		(pts
			(xy 119.38 152.4) (xy 124.46 152.4)
		)
		(stroke
			(width 0)
			(type default)
		)
	)
	(wire
		(pts
			(xy 119.38 40.64) (xy 121.92 40.64)
		)
		(stroke
			(width 0)
			(type default)
		)
	)
	(wire
		(pts
			(xy 81.28 46.99) (xy 90.17 46.99)
		)
		(stroke
			(width 0)
			(type default)
		)
	)
	(wire
		(pts
			(xy 238.76 116.84) (xy 255.27 116.84)
		)
		(stroke
			(width 0)
			(type default)
		)
	)
	(wire
		(pts
			(xy 119.38 101.6) (xy 119.38 104.14)
		)
		(stroke
			(width 0)
			(type default)
		)
	)
	(wire
		(pts
			(xy 354.33 45.72) (xy 363.22 45.72)
		)
		(stroke
			(width 0)
			(type default)
		)
	)
	(polyline
		(pts
			(xy 224.79 201.93) (xy 251.46 201.93)
		)
		(stroke
			(width 0)
			(type default)
		)
	)
	(wire
		(pts
			(xy 281.94 161.29) (xy 290.83 161.29)
		)
		(stroke
			(width 0)
			(type default)
		)
	)
	(bus
		(pts
			(xy 106.68 273.05) (xy 107.95 273.05)
		)
		(stroke
			(width 0)
			(type default)
		)
	)
	(wire
		(pts
			(xy 388.62 66.04) (xy 400.05 66.04)
		)
		(stroke
			(width 0)
			(type default)
		)
	)
	(wire
		(pts
			(xy 99.06 227.33) (xy 114.3 227.33)
		)
		(stroke
			(width 0)
			(type default)
		)
	)
	(wire
		(pts
			(xy 242.57 217.17) (xy 242.57 219.71)
		)
		(stroke
			(width 0)
			(type default)
		)
	)
	(wire
		(pts
			(xy 281.94 219.71) (xy 281.94 220.98)
		)
		(stroke
			(width 0)
			(type default)
		)
	)
	(polyline
		(pts
			(xy 273.05 190.5) (xy 273.05 203.2)
		)
		(stroke
			(width 0)
			(type default)
		)
	)
	(wire
		(pts
			(xy 118.11 38.1) (xy 121.92 38.1)
		)
		(stroke
			(width 0)
			(type default)
		)
	)
	(wire
		(pts
			(xy 351.79 208.28) (xy 351.79 212.09)
		)
		(stroke
			(width 0)
			(type default)
		)
	)
	(polyline
		(pts
			(xy 227.33 144.78) (xy 254 144.78)
		)
		(stroke
			(width 0)
			(type default)
		)
	)
	(wire
		(pts
			(xy 200.66 86.36) (xy 200.66 87.63)
		)
		(stroke
			(width 0)
			(type default)
		)
	)
	(wire
		(pts
			(xy 49.53 102.87) (xy 49.53 104.14)
		)
		(stroke
			(width 0)
			(type default)
		)
	)
	(wire
		(pts
			(xy 107.95 115.57) (xy 110.49 115.57)
		)
		(stroke
			(width 0)
			(type default)
		)
	)
	(wire
		(pts
			(xy 377.19 172.72) (xy 377.19 173.99)
		)
		(stroke
			(width 0)
			(type default)
		)
	)
	(wire
		(pts
			(xy 374.65 215.9) (xy 378.46 215.9)
		)
		(stroke
			(width 0)
			(type default)
		)
	)
	(wire
		(pts
			(xy 102.87 49.53) (xy 101.6 49.53)
		)
		(stroke
			(width 0)
			(type default)
		)
	)
	(wire
		(pts
			(xy 187.96 146.05) (xy 201.93 146.05)
		)
		(stroke
			(width 0)
			(type default)
		)
	)
	(wire
		(pts
			(xy 281.94 53.34) (xy 318.77 53.34)
		)
		(stroke
			(width 0)
			(type default)
		)
	)
	(polyline
		(pts
			(xy 118.11 250.19) (xy 118.11 267.97)
		)
		(stroke
			(width 0)
			(type default)
		)
	)
	(wire
		(pts
			(xy 242.57 198.12) (xy 242.57 200.66)
		)
		(stroke
			(width 0)
			(type default)
		)
	)
	(wire
		(pts
			(xy 46.99 39.37) (xy 55.88 39.37)
		)
		(stroke
			(width 0)
			(type default)
		)
	)
	(wire
		(pts
			(xy 204.47 240.03) (xy 204.47 242.57)
		)
		(stroke
			(width 0)
			(type default)
		)
	)
	(wire
		(pts
			(xy 379.73 45.72) (xy 388.62 45.72)
		)
		(stroke
			(width 0)
			(type default)
		)
	)
	(wire
		(pts
			(xy 119.38 115.57) (xy 124.46 115.57)
		)
		(stroke
			(width 0)
			(type default)
		)
	)
	(wire
		(pts
			(xy 110.49 212.09) (xy 110.49 214.63)
		)
		(stroke
			(width 0)
			(type default)
		)
	)
	(wire
		(pts
			(xy 403.86 40.64) (xy 403.86 45.72)
		)
		(stroke
			(width 0)
			(type default)
		)
	)
	(wire
		(pts
			(xy 105.41 118.11) (xy 105.41 104.14)
		)
		(stroke
			(width 0)
			(type default)
		)
	)
	(wire
		(pts
			(xy 129.54 93.98) (xy 140.97 93.98)
		)
		(stroke
			(width 0)
			(type default)
		)
	)
	(wire
		(pts
			(xy 242.57 212.09) (xy 242.57 213.36)
		)
		(stroke
			(width 0)
			(type default)
		)
	)
	(wire
		(pts
			(xy 189.23 189.23) (xy 189.23 191.77)
		)
		(stroke
			(width 0)
			(type default)
		)
	)
	(wire
		(pts
			(xy 339.09 53.34) (xy 350.52 53.34)
		)
		(stroke
			(width 0)
			(type default)
		)
	)
	(wire
		(pts
			(xy 99.06 222.25) (xy 119.38 222.25)
		)
		(stroke
			(width 0)
			(type default)
		)
	)
	(polyline
		(pts
			(xy 16.51 104.14) (xy 45.72 104.14)
		)
		(stroke
			(width 0)
			(type default)
		)
	)
	(wire
		(pts
			(xy 55.88 38.1) (xy 55.88 39.37)
		)
		(stroke
			(width 0)
			(type default)
		)
	)
	(polyline
		(pts
			(xy 72.39 54.61) (xy 72.39 72.39)
		)
		(stroke
			(width 0)
			(type default)
		)
	)
	(polyline
		(pts
			(xy 45.72 88.9) (xy 16.51 88.9)
		)
		(stroke
			(width 0)
			(type default)
		)
	)
	(polyline
		(pts
			(xy 45.72 96.52) (xy 45.72 99.06)
		)
		(stroke
			(width 0)
			(type default)
		)
	)
	(wire
		(pts
			(xy 118.11 62.23) (xy 118.11 64.77)
		)
		(stroke
			(width 0)
			(type default)
		)
	)
	(polyline
		(pts
			(xy 158.75 250.19) (xy 158.75 280.67)
		)
		(stroke
			(width 0)
			(type default)
		)
	)
	(wire
		(pts
			(xy 349.25 212.09) (xy 351.79 212.09)
		)
		(stroke
			(width 0)
			(type default)
		)
	)
	(polyline
		(pts
			(xy 43.18 180.34) (xy 16.51 180.34)
		)
		(stroke
			(width 0)
			(type default)
		)
	)
	(wire
		(pts
			(xy 110.49 143.51) (xy 110.49 152.4)
		)
		(stroke
			(width 0)
			(type default)
		)
	)
	(wire
		(pts
			(xy 256.54 236.22) (xy 256.54 238.76)
		)
		(stroke
			(width 0)
			(type default)
		)
	)
	(wire
		(pts
			(xy 337.82 31.75) (xy 341.63 31.75)
		)
		(stroke
			(width 0)
			(type default)
		)
	)
	(wire
		(pts
			(xy 179.07 39.37) (xy 180.34 39.37)
		)
		(stroke
			(width 0)
			(type default)
		)
	)
	(wire
		(pts
			(xy 346.71 116.84) (xy 346.71 121.92)
		)
		(stroke
			(width 0)
			(type default)
		)
	)
	(wire
		(pts
			(xy 303.53 171.45) (xy 303.53 177.8)
		)
		(stroke
			(width 0)
			(type default)
		)
	)
	(wire
		(pts
			(xy 68.58 140.97) (xy 71.12 140.97)
		)
		(stroke
			(width 0)
			(type default)
		)
	)
	(wire
		(pts
			(xy 50.8 143.51) (xy 68.58 143.51)
		)
		(stroke
			(width 0)
			(type default)
		)
	)
	(wire
		(pts
			(xy 245.11 133.35) (xy 245.11 135.89)
		)
		(stroke
			(width 0)
			(type default)
		)
	)
	(wire
		(pts
			(xy 290.83 161.29) (xy 290.83 166.37)
		)
		(stroke
			(width 0)
			(type default)
		)
	)
	(wire
		(pts
			(xy 290.83 177.8) (xy 303.53 177.8)
		)
		(stroke
			(width 0)
			(type default)
		)
	)
	(wire
		(pts
			(xy 71.12 132.08) (xy 71.12 133.35)
		)
		(stroke
			(width 0)
			(type default)
		)
	)
	(wire
		(pts
			(xy 118.11 38.1) (xy 118.11 53.34)
		)
		(stroke
			(width 0)
			(type default)
		)
	)
	(polyline
		(pts
			(xy 251.46 240.03) (xy 251.46 247.65)
		)
		(stroke
			(width 0)
			(type default)
		)
	)
	(wire
		(pts
			(xy 59.69 189.23) (xy 59.69 191.77)
		)
		(stroke
			(width 0)
			(type default)
		)
	)
	(wire
		(pts
			(xy 114.3 143.51) (xy 119.38 143.51)
		)
		(stroke
			(width 0)
			(type default)
		)
	)
	(wire
		(pts
			(xy 217.17 40.64) (xy 217.17 43.18)
		)
		(stroke
			(width 0)
			(type default)
		)
	)
	(wire
		(pts
			(xy 203.2 180.34) (xy 203.2 182.88)
		)
		(stroke
			(width 0)
			(type default)
		)
	)
	(wire
		(pts
			(xy 49.53 113.03) (xy 71.12 113.03)
		)
		(stroke
			(width 0)
			(type default)
		)
	)
	(wire
		(pts
			(xy 242.57 250.19) (xy 242.57 251.46)
		)
		(stroke
			(width 0)
			(type default)
		)
	)
	(wire
		(pts
			(xy 104.14 40.64) (xy 104.14 46.99)
		)
		(stroke
			(width 0)
			(type default)
		)
	)
	(wire
		(pts
			(xy 110.49 204.47) (xy 110.49 207.01)
		)
		(stroke
			(width 0)
			(type default)
		)
	)
	(wire
		(pts
			(xy 119.38 204.47) (xy 124.46 204.47)
		)
		(stroke
			(width 0)
			(type default)
		)
	)
	(bus
		(pts
			(xy 303.53 76.2) (xy 302.26 77.47)
		)
		(stroke
			(width 0)
			(type default)
		)
	)
	(wire
		(pts
			(xy 179.07 229.87) (xy 190.5 229.87)
		)
		(stroke
			(width 0)
			(type default)
		)
	)
	(wire
		(pts
			(xy 121.92 17.78) (xy 121.92 16.51)
		)
		(stroke
			(width 0)
			(type default)
		)
	)
	(polyline
		(pts
			(xy 254 153.67) (xy 227.33 153.67)
		)
		(stroke
			(width 0)
			(type default)
		)
	)
	(wire
		(pts
			(xy 237.49 238.76) (xy 242.57 238.76)
		)
		(stroke
			(width 0)
			(type default)
		)
	)
	(polyline
		(pts
			(xy 219.71 203.2) (xy 201.93 203.2)
		)
		(stroke
			(width 0)
			(type default)
		)
	)
	(wire
		(pts
			(xy 281.94 220.98) (xy 290.83 220.98)
		)
		(stroke
			(width 0)
			(type default)
		)
	)
	(wire
		(pts
			(xy 242.57 255.27) (xy 242.57 257.81)
		)
		(stroke
			(width 0)
			(type default)
		)
	)
	(wire
		(pts
			(xy 213.36 50.8) (xy 213.36 53.34)
		)
		(stroke
			(width 0)
			(type default)
		)
	)
	(wire
		(pts
			(xy 100.33 182.88) (xy 100.33 199.39)
		)
		(stroke
			(width 0)
			(type default)
		)
	)
	(wire
		(pts
			(xy 129.54 152.4) (xy 135.89 152.4)
		)
		(stroke
			(width 0)
			(type default)
		)
	)
	(bus
		(pts
			(xy 299.72 60.96) (xy 299.72 69.85)
		)
		(stroke
			(width 0)
			(type default)
		)
	)
	(wire
		(pts
			(xy 186.69 116.84) (xy 203.2 116.84)
		)
		(stroke
			(width 0)
			(type default)
		)
	)
	(wire
		(pts
			(xy 129.54 204.47) (xy 133.35 204.47)
		)
		(stroke
			(width 0)
			(type default)
		)
	)
	(wire
		(pts
			(xy 300.99 59.69) (xy 318.77 59.69)
		)
		(stroke
			(width 0)
			(type default)
		)
	)
	(wire
		(pts
			(xy 311.15 166.37) (xy 311.15 161.29)
		)
		(stroke
			(width 0)
			(type default)
		)
	)
	(bus
		(pts
			(xy 34.29 214.63) (xy 33.02 214.63)
		)
		(stroke
			(width 0)
			(type default)
		)
	)
	(polyline
		(pts
			(xy 199.39 200.66) (xy 199.39 209.55)
		)
		(stroke
			(width 0)
			(type default)
		)
	)
	(wire
		(pts
			(xy 90.17 46.99) (xy 90.17 49.53)
		)
		(stroke
			(width 0)
			(type default)
		)
	)
	(wire
		(pts
			(xy 177.8 133.35) (xy 187.96 133.35)
		)
		(stroke
			(width 0)
			(type default)
		)
	)
	(wire
		(pts
			(xy 242.57 228.6) (xy 242.57 231.14)
		)
		(stroke
			(width 0)
			(type default)
		)
	)
	(wire
		(pts
			(xy 309.88 119.38) (xy 309.88 127)
		)
		(stroke
			(width 0)
			(type default)
		)
	)
	(wire
		(pts
			(xy 105.41 193.04) (xy 110.49 193.04)
		)
		(stroke
			(width 0)
			(type default)
		)
	)
	(polyline
		(pts
			(xy 69.85 12.7) (xy 69.85 77.47)
		)
		(stroke
			(width 0)
			(type default)
		)
	)
	(wire
		(pts
			(xy 370.84 55.88) (xy 379.73 55.88)
		)
		(stroke
			(width 0)
			(type default)
		)
	)
	(wire
		(pts
			(xy 293.37 29.21) (xy 306.07 29.21)
		)
		(stroke
			(width 0)
			(type default)
		)
	)
	(wire
		(pts
			(xy 388.62 73.66) (xy 388.62 76.2)
		)
		(stroke
			(width 0)
			(type default)
		)
	)
	(wire
		(pts
			(xy 394.97 165.1) (xy 397.51 165.1)
		)
		(stroke
			(width 0)
			(type default)
		)
	)
	(wire
		(pts
			(xy 90.17 46.99) (xy 91.44 46.99)
		)
		(stroke
			(width 0)
			(type default)
		)
	)
	(wire
		(pts
			(xy 388.62 66.04) (xy 388.62 68.58)
		)
		(stroke
			(width 0)
			(type default)
		)
	)
	(wire
		(pts
			(xy 49.53 181.61) (xy 49.53 182.88)
		)
		(stroke
			(width 0)
			(type default)
		)
	)
	(wire
		(pts
			(xy 350.52 68.58) (xy 350.52 71.12)
		)
		(stroke
			(width 0)
			(type default)
		)
	)
	(wire
		(pts
			(xy 290.83 228.6) (xy 290.83 229.87)
		)
		(stroke
			(width 0)
			(type default)
		)
	)
	(wire
		(pts
			(xy 172.72 93.98) (xy 186.69 93.98)
		)
		(stroke
			(width 0)
			(type default)
		)
	)
	(wire
		(pts
			(xy 293.37 39.37) (xy 281.94 39.37)
		)
		(stroke
			(width 0)
			(type default)
		)
	)
	(wire
		(pts
			(xy 123.19 45.72) (xy 146.05 45.72)
		)
		(stroke
			(width 0)
			(type default)
		)
	)
	(polyline
		(pts
			(xy 218.44 137.16) (xy 218.44 149.86)
		)
		(stroke
			(width 0)
			(type default)
		)
	)
	(wire
		(pts
			(xy 99.06 146.05) (xy 102.87 146.05)
		)
		(stroke
			(width 0)
			(type default)
		)
	)
	(wire
		(pts
			(xy 81.28 46.99) (xy 81.28 48.26)
		)
		(stroke
			(width 0)
			(type default)
		)
	)
	(wire
		(pts
			(xy 238.76 113.03) (xy 238.76 116.84)
		)
		(stroke
			(width 0)
			(type default)
		)
	)
	(wire
		(pts
			(xy 299.72 161.29) (xy 303.53 161.29)
		)
		(stroke
			(width 0)
			(type default)
		)
	)
	(polyline
		(pts
			(xy 196.85 106.68) (xy 196.85 114.3)
		)
		(stroke
			(width 0)
			(type default)
		)
	)
	(wire
		(pts
			(xy 255.27 33.02) (xy 265.43 33.02)
		)
		(stroke
			(width 0)
			(type default)
		)
	)
	(wire
		(pts
			(xy 346.71 111.76) (xy 350.52 111.76)
		)
		(stroke
			(width 0)
			(type default)
		)
	)
	(wire
		(pts
			(xy 189.23 212.09) (xy 205.74 212.09)
		)
		(stroke
			(width 0)
			(type default)
		)
	)
	(wire
		(pts
			(xy 21.59 38.1) (xy 21.59 39.37)
		)
		(stroke
			(width 0)
			(type default)
		)
	)
	(polyline
		(pts
			(xy 189.23 48.26) (xy 222.25 48.26)
		)
		(stroke
			(width 0)
			(type default)
		)
	)
	(polyline
		(pts
			(xy 158.75 280.67) (xy 85.09 280.67)
		)
		(stroke
			(width 0)
			(type default)
		)
	)
	(wire
		(pts
			(xy 127 259.08) (xy 121.92 259.08)
		)
		(stroke
			(width 0)
			(type default)
		)
	)
	(wire
		(pts
			(xy 146.05 45.72) (xy 146.05 46.99)
		)
		(stroke
			(width 0)
			(type default)
		)
	)
	(wire
		(pts
			(xy 119.38 152.4) (xy 119.38 154.94)
		)
		(stroke
			(width 0)
			(type default)
		)
	)
	(wire
		(pts
			(xy 119.38 182.88) (xy 119.38 185.42)
		)
		(stroke
			(width 0)
			(type default)
		)
	)
	(bus
		(pts
			(xy 91.44 38.1) (xy 92.71 38.1)
		)
		(stroke
			(width 0)
			(type default)
		)
	)
	(wire
		(pts
			(xy 256.54 224.79) (xy 256.54 226.06)
		)
		(stroke
			(width 0)
			(type default)
		)
	)
	(wire
		(pts
			(xy 402.59 236.22) (xy 403.86 236.22)
		)
		(stroke
			(width 0)
			(type default)
		)
	)
	(polyline
		(pts
			(xy 71.12 77.47) (xy 273.05 77.47)
		)
		(stroke
			(width 0)
			(type default)
		)
	)
	(wire
		(pts
			(xy 290.83 229.87) (xy 290.83 231.14)
		)
		(stroke
			(width 0)
			(type default)
		)
	)
	(wire
		(pts
			(xy 389.89 165.1) (xy 391.16 165.1)
		)
		(stroke
			(width 0)
			(type default)
		)
	)
	(wire
		(pts
			(xy 119.38 25.4) (xy 121.92 25.4)
		)
		(stroke
			(width 0)
			(type default)
		)
	)
	(wire
		(pts
			(xy 339.09 68.58) (xy 350.52 68.58)
		)
		(stroke
			(width 0)
			(type default)
		)
	)
	(wire
		(pts
			(xy 252.73 93.98) (xy 252.73 97.79)
		)
		(stroke
			(width 0)
			(type default)
		)
	)
	(wire
		(pts
			(xy 238.76 105.41) (xy 238.76 107.95)
		)
		(stroke
			(width 0)
			(type default)
		)
	)
	(polyline
		(pts
			(xy 254 190.5) (xy 273.05 190.5)
		)
		(stroke
			(width 0)
			(type default)
		)
	)
	(wire
		(pts
			(xy 133.35 182.88) (xy 133.35 204.47)
		)
		(stroke
			(width 0)
			(type default)
		)
	)
	(polyline
		(pts
			(xy 171.45 200.66) (xy 199.39 200.66)
		)
		(stroke
			(width 0)
			(type default)
		)
	)
	(wire
		(pts
			(xy 205.74 265.43) (xy 212.09 265.43)
		)
		(stroke
			(width 0)
			(type default)
		)
	)
	(wire
		(pts
			(xy 104.14 40.64) (xy 119.38 40.64)
		)
		(stroke
			(width 0)
			(type default)
		)
	)
	(wire
		(pts
			(xy 354.33 55.88) (xy 363.22 55.88)
		)
		(stroke
			(width 0)
			(type default)
		)
	)
	(wire
		(pts
			(xy 245.11 48.26) (xy 271.78 48.26)
		)
		(stroke
			(width 0)
			(type default)
		)
	)
	(wire
		(pts
			(xy 102.87 204.47) (xy 99.06 204.47)
		)
		(stroke
			(width 0)
			(type default)
		)
	)
	(wire
		(pts
			(xy 377.19 170.18) (xy 377.19 172.72)
		)
		(stroke
			(width 0)
			(type default)
		)
	)
	(polyline
		(pts
			(xy 16.51 187.96) (xy 43.18 187.96)
		)
		(stroke
			(width 0)
			(type default)
		)
	)
	(wire
		(pts
			(xy 281.94 220.98) (xy 281.94 223.52)
		)
		(stroke
			(width 0)
			(type default)
		)
	)
	(polyline
		(pts
			(xy 248.92 114.3) (xy 220.98 114.3)
		)
		(stroke
			(width 0)
			(type default)
		)
	)
	(wire
		(pts
			(xy 349.25 229.87) (xy 351.79 229.87)
		)
		(stroke
			(width 0)
			(type default)
		)
	)
	(wire
		(pts
			(xy 374.65 215.9) (xy 374.65 218.44)
		)
		(stroke
			(width 0)
			(type default)
		)
	)
	(polyline
		(pts
			(xy 16.51 93.98) (xy 45.72 93.98)
		)
		(stroke
			(width 0)
			(type default)
		)
	)
	(wire
		(pts
			(xy 119.38 115.57) (xy 119.38 118.11)
		)
		(stroke
			(width 0)
			(type default)
		)
	)
	(wire
		(pts
			(xy 110.49 101.6) (xy 110.49 104.14)
		)
		(stroke
			(width 0)
			(type default)
		)
	)
	(wire
		(pts
			(xy 374.65 223.52) (xy 374.65 226.06)
		)
		(stroke
			(width 0)
			(type default)
		)
	)
	(polyline
		(pts
			(xy 251.46 95.25) (xy 251.46 107.95)
		)
		(stroke
			(width 0)
			(type default)
		)
	)
	(wire
		(pts
			(xy 99.06 199.39) (xy 100.33 199.39)
		)
		(stroke
			(width 0)
			(type default)
		)
	)
	(wire
		(pts
			(xy 25.4 201.93) (xy 49.53 201.93)
		)
		(stroke
			(width 0)
			(type default)
		)
	)
	(wire
		(pts
			(xy 129.54 133.35) (xy 137.16 133.35)
		)
		(stroke
			(width 0)
			(type default)
		)
	)
	(wire
		(pts
			(xy 327.66 73.66) (xy 327.66 77.47)
		)
		(stroke
			(width 0)
			(type default)
		)
	)
	(polyline
		(pts
			(xy 220.98 107.95) (xy 220.98 116.84)
		)
		(stroke
			(width 0)
			(type default)
		)
	)
	(wire
		(pts
			(xy 119.38 93.98) (xy 124.46 93.98)
		)
		(stroke
			(width 0)
			(type default)
		)
	)
	(wire
		(pts
			(xy 110.49 247.65) (xy 127 247.65)
		)
		(stroke
			(width 0)
			(type default)
		)
	)
	(wire
		(pts
			(xy 114.3 227.33) (xy 114.3 232.41)
		)
		(stroke
			(width 0)
			(type default)
		)
	)
	(wire
		(pts
			(xy 370.84 45.72) (xy 370.84 48.26)
		)
		(stroke
			(width 0)
			(type default)
		)
	)
	(wire
		(pts
			(xy 59.69 102.87) (xy 49.53 102.87)
		)
		(stroke
			(width 0)
			(type default)
		)
	)
	(wire
		(pts
			(xy 151.13 259.08) (xy 151.13 261.62)
		)
		(stroke
			(width 0)
			(type default)
		)
	)
	(wire
		(pts
			(xy 100.33 64.77) (xy 105.41 64.77)
		)
		(stroke
			(width 0)
			(type default)
		)
	)
	(wire
		(pts
			(xy 69.85 110.49) (xy 71.12 110.49)
		)
		(stroke
			(width 0)
			(type default)
		)
	)
	(wire
		(pts
			(xy 201.93 127) (xy 201.93 129.54)
		)
		(stroke
			(width 0)
			(type default)
		)
	)
	(wire
		(pts
			(xy 107.95 123.19) (xy 107.95 115.57)
		)
		(stroke
			(width 0)
			(type default)
		)
	)
	(wire
		(pts
			(xy 336.55 177.8) (xy 341.63 177.8)
		)
		(stroke
			(width 0)
			(type default)
		)
	)
	(polyline
		(pts
			(xy 22.86 182.88) (xy 22.86 184.15)
		)
		(stroke
			(width 0)
			(type default)
		)
	)
	(wire
		(pts
			(xy 341.63 161.29) (xy 341.63 153.67)
		)
		(stroke
			(width 0)
			(type default)
		)
	)
	(wire
		(pts
			(xy 55.88 49.53) (xy 55.88 52.07)
		)
		(stroke
			(width 0)
			(type default)
		)
	)
	(wire
		(pts
			(xy 349.25 215.9) (xy 351.79 215.9)
		)
		(stroke
			(width 0)
			(type default)
		)
	)
	(wire
		(pts
			(xy 100.33 93.98) (xy 100.33 110.49)
		)
		(stroke
			(width 0)
			(type default)
		)
	)
	(wire
		(pts
			(xy 124.46 17.78) (xy 124.46 19.05)
		)
		(stroke
			(width 0)
			(type default)
		)
	)
	(wire
		(pts
			(xy 119.38 232.41) (xy 119.38 233.68)
		)
		(stroke
			(width 0)
			(type default)
		)
	)
	(wire
		(pts
			(xy 173.99 232.41) (xy 176.53 232.41)
		)
		(stroke
			(width 0)
			(type default)
		)
	)
	(polyline
		(pts
			(xy 30.48 91.44) (xy 30.48 104.14)
		)
		(stroke
			(width 0)
			(type default)
		)
	)
	(wire
		(pts
			(xy 400.05 54.61) (xy 400.05 58.42)
		)
		(stroke
			(width 0)
			(type default)
		)
	)
	(polyline
		(pts
			(xy 222.25 48.26) (xy 222.25 66.04)
		)
		(stroke
			(width 0)
			(type default)
		)
	)
	(wire
		(pts
			(xy 124.46 17.78) (xy 121.92 17.78)
		)
		(stroke
			(width 0)
			(type default)
		)
	)
	(wire
		(pts
			(xy 129.54 222.25) (xy 133.35 222.25)
		)
		(stroke
			(width 0)
			(type default)
		)
	)
	(wire
		(pts
			(xy 95.25 35.56) (xy 118.11 35.56)
		)
		(stroke
			(width 0)
			(type default)
		)
	)
	(wire
		(pts
			(xy 312.42 196.85) (xy 312.42 199.39)
		)
		(stroke
			(width 0)
			(type default)
		)
	)
	(wire
		(pts
			(xy 110.49 182.88) (xy 110.49 185.42)
		)
		(stroke
			(width 0)
			(type default)
		)
	)
	(wire
		(pts
			(xy 217.17 33.02) (xy 217.17 35.56)
		)
		(stroke
			(width 0)
			(type default)
		)
	)
	(wire
		(pts
			(xy 146.05 52.07) (xy 146.05 53.34)
		)
		(stroke
			(width 0)
			(type default)
		)
	)
	(wire
		(pts
			(xy 133.35 181.61) (xy 133.35 182.88)
		)
		(stroke
			(width 0)
			(type default)
		)
	)
	(wire
		(pts
			(xy 314.96 45.72) (xy 318.77 45.72)
		)
		(stroke
			(width 0)
			(type default)
		)
	)
	(wire
		(pts
			(xy 304.8 63.5) (xy 318.77 63.5)
		)
		(stroke
			(width 0)
			(type default)
		)
	)
	(wire
		(pts
			(xy 171.45 242.57) (xy 176.53 242.57)
		)
		(stroke
			(width 0)
			(type default)
		)
	)
	(wire
		(pts
			(xy 306.07 29.21) (xy 306.07 31.75)
		)
		(stroke
			(width 0)
			(type default)
		)
	)
	(wire
		(pts
			(xy 181.61 105.41) (xy 186.69 105.41)
		)
		(stroke
			(width 0)
			(type default)
		)
	)
	(wire
		(pts
			(xy 59.69 93.98) (xy 69.85 93.98)
		)
		(stroke
			(width 0)
			(type default)
		)
	)
	(wire
		(pts
			(xy 265.43 53.34) (xy 271.78 53.34)
		)
		(stroke
			(width 0)
			(type default)
		)
	)
	(wire
		(pts
			(xy 341.63 161.29) (xy 341.63 163.83)
		)
		(stroke
			(width 0)
			(type default)
		)
	)
	(bus
		(pts
			(xy 303.53 64.77) (xy 303.53 67.31)
		)
		(stroke
			(width 0)
			(type default)
		)
	)
	(wire
		(pts
			(xy 402.59 238.76) (xy 403.86 238.76)
		)
		(stroke
			(width 0)
			(type default)
		)
	)
	(bus
		(pts
			(xy 49.53 146.05) (xy 49.53 144.78)
		)
		(stroke
			(width 0)
			(type default)
		)
	)
	(wire
		(pts
			(xy 186.69 113.03) (xy 186.69 116.84)
		)
		(stroke
			(width 0)
			(type default)
		)
	)
	(wire
		(pts
			(xy 119.38 193.04) (xy 119.38 194.31)
		)
		(stroke
			(width 0)
			(type default)
		)
	)
	(wire
		(pts
			(xy 114.3 138.43) (xy 114.3 143.51)
		)
		(stroke
			(width 0)
			(type default)
		)
	)
	(polyline
		(pts
			(xy 85.09 267.97) (xy 118.11 267.97)
		)
		(stroke
			(width 0)
			(type default)
		)
	)
	(bus
		(pts
			(xy 44.45 252.73) (xy 43.18 254)
		)
		(stroke
			(width 0)
			(type default)
		)
	)
	(bus
		(pts
			(xy 46.99 147.32) (xy 48.26 147.32)
		)
		(stroke
			(width 0)
			(type default)
		)
	)
	(bus
		(pts
			(xy 299.72 69.85) (xy 298.45 71.12)
		)
		(stroke
			(width 0)
			(type default)
		)
	)
	(wire
		(pts
			(xy 311.15 218.44) (xy 325.12 218.44)
		)
		(stroke
			(width 0)
			(type default)
		)
	)
	(polyline
		(pts
			(xy 27.94 182.88) (xy 27.94 193.04)
		)
		(stroke
			(width 0)
			(type default)
		)
	)
	(wire
		(pts
			(xy 238.76 121.92) (xy 238.76 124.46)
		)
		(stroke
			(width 0)
			(type default)
		)
	)
	(wire
		(pts
			(xy 190.5 242.57) (xy 204.47 242.57)
		)
		(stroke
			(width 0)
			(type default)
		)
	)
	(polyline
		(pts
			(xy 199.39 209.55) (xy 171.45 209.55)
		)
		(stroke
			(width 0)
			(type default)
		)
	)
	(wire
		(pts
			(xy 242.57 208.28) (xy 242.57 212.09)
		)
		(stroke
			(width 0)
			(type default)
		)
	)
	(wire
		(pts
			(xy 379.73 45.72) (xy 379.73 48.26)
		)
		(stroke
			(width 0)
			(type default)
		)
	)
	(wire
		(pts
			(xy 25.4 201.93) (xy 25.4 223.52)
		)
		(stroke
			(width 0)
			(type default)
		)
	)
	(wire
		(pts
			(xy 153.67 38.1) (xy 153.67 35.56)
		)
		(stroke
			(width 0)
			(type default)
		)
	)
	(wire
		(pts
			(xy 242.57 53.34) (xy 265.43 53.34)
		)
		(stroke
			(width 0)
			(type default)
		)
	)
	(polyline
		(pts
			(xy 199.39 137.16) (xy 218.44 137.16)
		)
		(stroke
			(width 0)
			(type default)
		)
	)
	(wire
		(pts
			(xy 311.15 166.37) (xy 314.96 166.37)
		)
		(stroke
			(width 0)
			(type default)
		)
	)
	(wire
		(pts
			(xy 99.06 128.27) (xy 102.87 128.27)
		)
		(stroke
			(width 0)
			(type default)
		)
	)
	(wire
		(pts
			(xy 146.05 53.34) (xy 153.67 53.34)
		)
		(stroke
			(width 0)
			(type default)
		)
	)
	(wire
		(pts
			(xy 119.38 222.25) (xy 124.46 222.25)
		)
		(stroke
			(width 0)
			(type default)
		)
	)
	(bus
		(pts
			(xy 31.75 219.71) (xy 31.75 217.17)
		)
		(stroke
			(width 0)
			(type default)
		)
	)
	(wire
		(pts
			(xy 302.26 220.98) (xy 302.26 223.52)
		)
		(stroke
			(width 0)
			(type default)
		)
	)
	(wire
		(pts
			(xy 238.76 105.41) (xy 252.73 105.41)
		)
		(stroke
			(width 0)
			(type default)
		)
	)
	(wire
		(pts
			(xy 351.79 236.22) (xy 351.79 229.87)
		)
		(stroke
			(width 0)
			(type default)
		)
	)
	(wire
		(pts
			(xy 364.49 215.9) (xy 374.65 215.9)
		)
		(stroke
			(width 0)
			(type default)
		)
	)
	(polyline
		(pts
			(xy 185.42 13.97) (xy 185.42 31.75)
		)
		(stroke
			(width 0)
			(type default)
		)
	)
	(wire
		(pts
			(xy 403.86 238.76) (xy 403.86 242.57)
		)
		(stroke
			(width 0)
			(type default)
		)
	)
	(polyline
		(pts
			(xy 251.46 247.65) (xy 224.79 247.65)
		)
		(stroke
			(width 0)
			(type default)
		)
	)
	(wire
		(pts
			(xy 153.67 38.1) (xy 153.67 46.99)
		)
		(stroke
			(width 0)
			(type default)
		)
	)
	(wire
		(pts
			(xy 351.79 215.9) (xy 355.6 215.9)
		)
		(stroke
			(width 0)
			(type default)
		)
	)
	(wire
		(pts
			(xy 402.59 233.68) (xy 403.86 233.68)
		)
		(stroke
			(width 0)
			(type default)
		)
	)
	(polyline
		(pts
			(xy 16.51 190.5) (xy 16.51 193.04)
		)
		(stroke
			(width 0)
			(type default)
		)
	)
	(wire
		(pts
			(xy 363.22 45.72) (xy 370.84 45.72)
		)
		(stroke
			(width 0)
			(type default)
		)
	)
	(wire
		(pts
			(xy 200.66 102.87) (xy 200.66 105.41)
		)
		(stroke
			(width 0)
			(type default)
		)
	)
	(polyline
		(pts
			(xy 118.11 250.19) (xy 158.75 250.19)
		)
		(stroke
			(width 0)
			(type default)
		)
	)
	(polyline
		(pts
			(xy 16.51 88.9) (xy 16.51 99.06)
		)
		(stroke
			(width 0)
			(type default)
		)
	)
	(wire
		(pts
			(xy 190.5 240.03) (xy 190.5 242.57)
		)
		(stroke
			(width 0)
			(type default)
		)
	)
	(wire
		(pts
			(xy 242.57 238.76) (xy 242.57 241.3)
		)
		(stroke
			(width 0)
			(type default)
		)
	)
	(wire
		(pts
			(xy 186.69 116.84) (xy 186.69 118.11)
		)
		(stroke
			(width 0)
			(type default)
		)
	)
	(wire
		(pts
			(xy 186.69 121.92) (xy 186.69 124.46)
		)
		(stroke
			(width 0)
			(type default)
		)
	)
	(wire
		(pts
			(xy 355.6 215.9) (xy 355.6 218.44)
		)
		(stroke
			(width 0)
			(type default)
		)
	)
	(polyline
		(pts
			(xy 254 144.78) (xy 254 153.67)
		)
		(stroke
			(width 0)
			(type default)
		)
	)
	(polyline
		(pts
			(xy 273.05 203.2) (xy 254 203.2)
		)
		(stroke
			(width 0)
			(type default)
		)
	)
	(wire
		(pts
			(xy 384.81 107.95) (xy 384.81 111.76)
		)
		(stroke
			(width 0)
			(type default)
		)
	)
	(wire
		(pts
			(xy 110.49 255.27) (xy 110.49 259.08)
		)
		(stroke
			(width 0)
			(type default)
		)
	)
	(wire
		(pts
			(xy 190.5 255.27) (xy 190.5 256.54)
		)
		(stroke
			(width 0)
			(type default)
		)
	)
	(wire
		(pts
			(xy 68.58 146.05) (xy 68.58 143.51)
		)
		(stroke
			(width 0)
			(type default)
		)
	)
	(wire
		(pts
			(xy 119.38 133.35) (xy 124.46 133.35)
		)
		(stroke
			(width 0)
			(type default)
		)
	)
	(wire
		(pts
			(xy 105.41 207.01) (xy 105.41 193.04)
		)
		(stroke
			(width 0)
			(type default)
		)
	)
	(wire
		(pts
			(xy 121.92 266.7) (xy 121.92 269.24)
		)
		(stroke
			(width 0)
			(type default)
		)
	)
	(polyline
		(pts
			(xy 120.65 54.61) (xy 120.65 72.39)
		)
		(stroke
			(width 0)
			(type default)
		)
	)
	(wire
		(pts
			(xy 71.12 220.98) (xy 71.12 222.25)
		)
		(stroke
			(width 0)
			(type default)
		)
	)
	(wire
		(pts
			(xy 203.2 196.85) (xy 203.2 199.39)
		)
		(stroke
			(width 0)
			(type default)
		)
	)
	(wire
		(pts
			(xy 281.94 53.34) (xy 281.94 55.88)
		)
		(stroke
			(width 0)
			(type default)
		)
	)
	(wire
		(pts
			(xy 157.48 17.78) (xy 157.48 31.75)
		)
		(stroke
			(width 0)
			(type default)
		)
	)
	(wire
		(pts
			(xy 238.76 93.98) (xy 238.76 97.79)
		)
		(stroke
			(width 0)
			(type default)
		)
	)
	(wire
		(pts
			(xy 129.54 182.88) (xy 133.35 182.88)
		)
		(stroke
			(width 0)
			(type default)
		)
	)
	(wire
		(pts
			(xy 110.49 115.57) (xy 110.49 118.11)
		)
		(stroke
			(width 0)
			(type default)
		)
	)
	(wire
		(pts
			(xy 304.8 111.76) (xy 309.88 111.76)
		)
		(stroke
			(width 0)
			(type default)
		)
	)
	(wire
		(pts
			(xy 373.38 236.22) (xy 386.08 236.22)
		)
		(stroke
			(width 0)
			(type default)
		)
	)
	(wire
		(pts
			(xy 204.47 229.87) (xy 204.47 231.14)
		)
		(stroke
			(width 0)
			(type default)
		)
	)
	(wire
		(pts
			(xy 321.31 212.09) (xy 325.12 212.09)
		)
		(stroke
			(width 0)
			(type default)
		)
	)
	(wire
		(pts
			(xy 119.38 25.4) (xy 119.38 27.94)
		)
		(stroke
			(width 0)
			(type default)
		)
	)
	(wire
		(pts
			(xy 200.66 93.98) (xy 217.17 93.98)
		)
		(stroke
			(width 0)
			(type default)
		)
	)
	(wire
		(pts
			(xy 303.53 177.8) (xy 323.85 177.8)
		)
		(stroke
			(width 0)
			(type default)
		)
	)
	(wire
		(pts
			(xy 217.17 33.02) (xy 232.41 33.02)
		)
		(stroke
			(width 0)
			(type default)
		)
	)
	(wire
		(pts
			(xy 245.11 44.45) (xy 245.11 48.26)
		)
		(stroke
			(width 0)
			(type default)
		)
	)
	(wire
		(pts
			(xy 360.68 236.22) (xy 360.68 234.95)
		)
		(stroke
			(width 0)
			(type default)
		)
	)
	(wire
		(pts
			(xy 252.73 86.36) (xy 252.73 87.63)
		)
		(stroke
			(width 0)
			(type default)
		)
	)
	(wire
		(pts
			(xy 312.42 237.49) (xy 312.42 238.76)
		)
		(stroke
			(width 0)
			(type default)
		)
	)
	(wire
		(pts
			(xy 127 247.65) (xy 127 259.08)
		)
		(stroke
			(width 0)
			(type default)
		)
	)
	(polyline
		(pts
			(xy 12.7 77.47) (xy 69.85 77.47)
		)
		(stroke
			(width 0)
			(type default)
		)
	)
	(wire
		(pts
			(xy 255.27 33.02) (xy 255.27 39.37)
		)
		(stroke
			(width 0)
			(type default)
		)
	)
	(polyline
		(pts
			(xy 196.85 156.21) (xy 170.18 156.21)
		)
		(stroke
			(width 0)
			(type default)
		)
	)
	(polyline
		(pts
			(xy 22.86 184.15) (xy 22.86 193.04)
		)
		(stroke
			(width 0)
			(type default)
		)
	)
	(wire
		(pts
			(xy 190.5 242.57) (xy 190.5 245.11)
		)
		(stroke
			(width 0)
			(type default)
		)
	)
	(wire
		(pts
			(xy 388.62 45.72) (xy 388.62 54.61)
		)
		(stroke
			(width 0)
			(type default)
		)
	)
	(wire
		(pts
			(xy 151.13 266.7) (xy 151.13 269.24)
		)
		(stroke
			(width 0)
			(type default)
		)
	)
	(wire
		(pts
			(xy 323.85 179.07) (xy 323.85 177.8)
		)
		(stroke
			(width 0)
			(type default)
		)
	)
	(wire
		(pts
			(xy 242.57 238.76) (xy 256.54 238.76)
		)
		(stroke
			(width 0)
			(type default)
		)
	)
	(wire
		(pts
			(xy 146.05 269.24) (xy 146.05 270.51)
		)
		(stroke
			(width 0)
			(type default)
		)
	)
	(wire
		(pts
			(xy 140.97 93.98) (xy 140.97 88.9)
		)
		(stroke
			(width 0)
			(type default)
		)
	)
	(wire
		(pts
			(xy 349.25 218.44) (xy 351.79 218.44)
		)
		(stroke
			(width 0)
			(type default)
		)
	)
	(wire
		(pts
			(xy 119.38 222.25) (xy 119.38 224.79)
		)
		(stroke
			(width 0)
			(type default)
		)
	)
	(wire
		(pts
			(xy 355.6 226.06) (xy 364.49 226.06)
		)
		(stroke
			(width 0)
			(type default)
		)
	)
	(wire
		(pts
			(xy 237.49 200.66) (xy 242.57 200.66)
		)
		(stroke
			(width 0)
			(type default)
		)
	)
	(wire
		(pts
			(xy 64.77 229.87) (xy 71.12 229.87)
		)
		(stroke
			(width 0)
			(type default)
		)
	)
	(wire
		(pts
			(xy 312.42 204.47) (xy 312.42 205.74)
		)
		(stroke
			(width 0)
			(type default)
		)
	)
	(wire
		(pts
			(xy 67.31 209.55) (xy 71.12 209.55)
		)
		(stroke
			(width 0)
			(type default)
		)
	)
	(wire
		(pts
			(xy 189.23 35.56) (xy 189.23 50.8)
		)
		(stroke
			(width 0)
			(type default)
		)
	)
	(wire
		(pts
			(xy 229.87 93.98) (xy 238.76 93.98)
		)
		(stroke
			(width 0)
			(type default)
		)
	)
	(wire
		(pts
			(xy 189.23 196.85) (xy 189.23 199.39)
		)
		(stroke
			(width 0)
			(type default)
		)
	)
	(wire
		(pts
			(xy 49.53 41.91) (xy 49.53 52.07)
		)
		(stroke
			(width 0)
			(type default)
		)
	)
	(polyline
		(pts
			(xy 248.92 106.68) (xy 248.92 114.3)
		)
		(stroke
			(width 0)
			(type default)
		)
	)
	(wire
		(pts
			(xy 377.19 172.72) (xy 389.89 172.72)
		)
		(stroke
			(width 0)
			(type default)
		)
	)
	(wire
		(pts
			(xy 332.74 161.29) (xy 341.63 161.29)
		)
		(stroke
			(width 0)
			(type default)
		)
	)
	(wire
		(pts
			(xy 341.63 45.72) (xy 345.44 45.72)
		)
		(stroke
			(width 0)
			(type default)
		)
	)
	(wire
		(pts
			(xy 49.53 92.71) (xy 49.53 93.98)
		)
		(stroke
			(width 0)
			(type default)
		)
	)
	(wire
		(pts
			(xy 373.38 161.29) (xy 377.19 161.29)
		)
		(stroke
			(width 0)
			(type default)
		)
	)
	(wire
		(pts
			(xy 151.13 259.08) (xy 151.13 247.65)
		)
		(stroke
			(width 0)
			(type default)
		)
	)
	(wire
		(pts
			(xy 383.54 233.68) (xy 386.08 233.68)
		)
		(stroke
			(width 0)
			(type default)
		)
	)
	(wire
		(pts
			(xy 293.37 29.21) (xy 293.37 31.75)
		)
		(stroke
			(width 0)
			(type default)
		)
	)
	(wire
		(pts
			(xy 147.32 38.1) (xy 146.05 38.1)
		)
		(stroke
			(width 0)
			(type default)
		)
	)
	(wire
		(pts
			(xy 187.96 143.51) (xy 187.96 146.05)
		)
		(stroke
			(width 0)
			(type default)
		)
	)
	(wire
		(pts
			(xy 281.94 60.96) (xy 281.94 63.5)
		)
		(stroke
			(width 0)
			(type default)
		)
	)
	(wire
		(pts
			(xy 355.6 243.84) (xy 355.6 245.11)
		)
		(stroke
			(width 0)
			(type default)
		)
	)
	(wire
		(pts
			(xy 312.42 229.87) (xy 302.26 229.87)
		)
		(stroke
			(width 0)
			(type default)
		)
	)
	(wire
		(pts
			(xy 17.78 129.54) (xy 71.12 129.54)
		)
		(stroke
			(width 0)
			(type default)
		)
	)
	(wire
		(pts
			(xy 290.83 220.98) (xy 302.26 220.98)
		)
		(stroke
			(width 0)
			(type default)
		)
	)
	(polyline
		(pts
			(xy 201.93 233.68) (xy 201.93 246.38)
		)
		(stroke
			(width 0)
			(type default)
		)
	)
	(wire
		(pts
			(xy 186.69 105.41) (xy 200.66 105.41)
		)
		(stroke
			(width 0)
			(type default)
		)
	)
	(wire
		(pts
			(xy 309.88 127) (xy 317.5 127)
		)
		(stroke
			(width 0)
			(type default)
		)
	)
	(wire
		(pts
			(xy 121.92 17.78) (xy 121.92 25.4)
		)
		(stroke
			(width 0)
			(type default)
		)
	)
	(wire
		(pts
			(xy 99.06 123.19) (xy 107.95 123.19)
		)
		(stroke
			(width 0)
			(type default)
		)
	)
	(wire
		(pts
			(xy 379.73 53.34) (xy 379.73 55.88)
		)
		(stroke
			(width 0)
			(type default)
		)
	)
	(wire
		(pts
			(xy 49.53 100.33) (xy 49.53 102.87)
		)
		(stroke
			(width 0)
			(type default)
		)
	)
	(wire
		(pts
			(xy 339.09 60.96) (xy 356.87 60.96)
		)
		(stroke
			(width 0)
			(type default)
		)
	)
	(wire
		(pts
			(xy 355.6 236.22) (xy 360.68 236.22)
		)
		(stroke
			(width 0)
			(type default)
		)
	)
	(wire
		(pts
			(xy 119.38 160.02) (xy 119.38 162.56)
		)
		(stroke
			(width 0)
			(type default)
		)
	)
	(wire
		(pts
			(xy 69.85 146.05) (xy 69.85 148.59)
		)
		(stroke
			(width 0)
			(type default)
		)
	)
	(wire
		(pts
			(xy 50.8 140.97) (xy 68.58 140.97)
		)
		(stroke
			(width 0)
			(type default)
		)
	)
	(wire
		(pts
			(xy 351.79 165.1) (xy 355.6 165.1)
		)
		(stroke
			(width 0)
			(type default)
		)
	)
	(wire
		(pts
			(xy 179.07 35.56) (xy 189.23 35.56)
		)
		(stroke
			(width 0)
			(type default)
		)
	)
	(wire
		(pts
			(xy 99.06 110.49) (xy 100.33 110.49)
		)
		(stroke
			(width 0)
			(type default)
		)
	)
	(bus
		(pts
			(xy 16.51 128.27) (xy 16.51 130.81)
		)
		(stroke
			(width 0)
			(type default)
		)
	)
	(wire
		(pts
			(xy 110.49 182.88) (xy 118.11 182.88)
		)
		(stroke
			(width 0)
			(type default)
		)
	)
	(bus
		(pts
			(xy 297.18 71.12) (xy 298.45 71.12)
		)
		(stroke
			(width 0)
			(type default)
		)
	)
	(wire
		(pts
			(xy 330.2 114.3) (xy 330.2 111.76)
		)
		(stroke
			(width 0)
			(type default)
		)
	)
	(wire
		(pts
			(xy 154.94 16.51) (xy 154.94 17.78)
		)
		(stroke
			(width 0)
			(type default)
		)
	)
	(wire
		(pts
			(xy 102.87 224.79) (xy 99.06 224.79)
		)
		(stroke
			(width 0)
			(type default)
		)
	)
	(wire
		(pts
			(xy 49.53 182.88) (xy 49.53 184.15)
		)
		(stroke
			(width 0)
			(type default)
		)
	)
	(wire
		(pts
			(xy 312.42 229.87) (xy 312.42 232.41)
		)
		(stroke
			(width 0)
			(type default)
		)
	)
	(wire
		(pts
			(xy 200.66 93.98) (xy 200.66 97.79)
		)
		(stroke
			(width 0)
			(type default)
		)
	)
	(wire
		(pts
			(xy 370.84 53.34) (xy 370.84 55.88)
		)
		(stroke
			(width 0)
			(type default)
		)
	)
	(wire
		(pts
			(xy 242.57 246.38) (xy 242.57 250.19)
		)
		(stroke
			(width 0)
			(type default)
		)
	)
	(wire
		(pts
			(xy 142.24 62.23) (xy 142.24 66.04)
		)
		(stroke
			(width 0)
			(type default)
		)
	)
	(wire
		(pts
			(xy 303.53 161.29) (xy 303.53 166.37)
		)
		(stroke
			(width 0)
			(type default)
		)
	)
	(wire
		(pts
			(xy 139.7 38.1) (xy 146.05 38.1)
		)
		(stroke
			(width 0)
			(type default)
		)
	)
	(wire
		(pts
			(xy 373.38 60.96) (xy 373.38 66.04)
		)
		(stroke
			(width 0)
			(type default)
		)
	)
	(wire
		(pts
			(xy 311.15 161.29) (xy 314.96 161.29)
		)
		(stroke
			(width 0)
			(type default)
		)
	)
	(wire
		(pts
			(xy 187.96 133.35) (xy 187.96 138.43)
		)
		(stroke
			(width 0)
			(type default)
		)
	)
	(wire
		(pts
			(xy 256.54 226.06) (xy 270.51 226.06)
		)
		(stroke
			(width 0)
			(type default)
		)
	)
	(polyline
		(pts
			(xy 269.24 97.79) (xy 269.24 110.49)
		)
		(stroke
			(width 0)
			(type default)
		)
	)
	(wire
		(pts
			(xy 64.77 240.03) (xy 64.77 250.19)
		)
		(stroke
			(width 0)
			(type default)
		)
	)
	(wire
		(pts
			(xy 252.73 93.98) (xy 269.24 93.98)
		)
		(stroke
			(width 0)
			(type default)
		)
	)
	(wire
		(pts
			(xy 384.81 153.67) (xy 396.24 153.67)
		)
		(stroke
			(width 0)
			(type default)
		)
	)
	(wire
		(pts
			(xy 341.63 31.75) (xy 341.63 45.72)
		)
		(stroke
			(width 0)
			(type default)
		)
	)
	(wire
		(pts
			(xy 401.32 207.01) (xy 401.32 209.55)
		)
		(stroke
			(width 0)
			(type default)
		)
	)
	(wire
		(pts
			(xy 55.88 39.37) (xy 55.88 44.45)
		)
		(stroke
			(width 0)
			(type default)
		)
	)
	(wire
		(pts
			(xy 110.49 247.65) (xy 110.49 250.19)
		)
		(stroke
			(width 0)
			(type default)
		)
	)
	(wire
		(pts
			(xy 154.94 17.78) (xy 154.94 19.05)
		)
		(stroke
			(width 0)
			(type default)
		)
	)
	(wire
		(pts
			(xy 190.5 260.35) (xy 190.5 261.62)
		)
		(stroke
			(width 0)
			(type default)
		)
	)
	(wire
		(pts
			(xy 33.02 218.44) (xy 71.12 218.44)
		)
		(stroke
			(width 0)
			(type default)
		)
	)
	(polyline
		(pts
			(xy 199.39 137.16) (xy 199.39 149.86)
		)
		(stroke
			(width 0)
			(type default)
		)
	)
	(wire
		(pts
			(xy 335.28 234.95) (xy 335.28 237.49)
		)
		(stroke
			(width 0)
			(type default)
		)
	)
	(polyline
		(pts
			(xy 12.7 78.74) (xy 273.05 78.74)
		)
		(stroke
			(width 0)
			(type default)
		)
	)
	(wire
		(pts
			(xy 121.92 25.4) (xy 121.92 35.56)
		)
		(stroke
			(width 0)
			(type default)
		)
	)
	(polyline
		(pts
			(xy 269.24 107.95) (xy 251.46 107.95)
		)
		(stroke
			(width 0)
			(type default)
		)
	)
	(wire
		(pts
			(xy 328.93 31.75) (xy 328.93 40.64)
		)
		(stroke
			(width 0)
			(type default)
		)
	)
	(wire
		(pts
			(xy 317.5 124.46) (xy 317.5 127)
		)
		(stroke
			(width 0)
			(type default)
		)
	)
	(polyline
		(pts
			(xy 45.72 91.44) (xy 25.4 91.44)
		)
		(stroke
			(width 0)
			(type default)
		)
	)
	(wire
		(pts
			(xy 351.79 218.44) (xy 351.79 215.9)
		)
		(stroke
			(width 0)
			(type default)
		)
	)
	(wire
		(pts
			(xy 341.63 153.67) (xy 379.73 153.67)
		)
		(stroke
			(width 0)
			(type default)
		)
	)
	(wire
		(pts
			(xy 242.57 236.22) (xy 242.57 238.76)
		)
		(stroke
			(width 0)
			(type default)
		)
	)
	(wire
		(pts
			(xy 99.06 118.11) (xy 105.41 118.11)
		)
		(stroke
			(width 0)
			(type default)
		)
	)
	(wire
		(pts
			(xy 90.17 49.53) (xy 91.44 49.53)
		)
		(stroke
			(width 0)
			(type default)
		)
	)
	(polyline
		(pts
			(xy 168.91 106.68) (xy 168.91 114.3)
		)
		(stroke
			(width 0)
			(type default)
		)
	)
	(wire
		(pts
			(xy 312.42 196.85) (xy 321.31 196.85)
		)
		(stroke
			(width 0)
			(type default)
		)
	)
	(wire
		(pts
			(xy 139.7 35.56) (xy 153.67 35.56)
		)
		(stroke
			(width 0)
			(type default)
		)
	)
	(wire
		(pts
			(xy 339.09 45.72) (xy 341.63 45.72)
		)
		(stroke
			(width 0)
			(type default)
		)
	)
	(wire
		(pts
			(xy 368.3 111.76) (xy 384.81 111.76)
		)
		(stroke
			(width 0)
			(type default)
		)
	)
	(bus
		(pts
			(xy 16.51 123.19) (xy 17.78 121.92)
		)
		(stroke
			(width 0)
			(type default)
		)
	)
	(wire
		(pts
			(xy 212.09 273.05) (xy 212.09 275.59)
		)
		(stroke
			(width 0)
			(type default)
		)
	)
	(wire
		(pts
			(xy 25.4 41.91) (xy 25.4 39.37)
		)
		(stroke
			(width 0)
			(type default)
		)
	)
	(wire
		(pts
			(xy 256.54 198.12) (xy 256.54 200.66)
		)
		(stroke
			(width 0)
			(type default)
		)
	)
	(wire
		(pts
			(xy 397.51 40.64) (xy 403.86 40.64)
		)
		(stroke
			(width 0)
			(type default)
		)
	)
	(wire
		(pts
			(xy 187.96 163.83) (xy 187.96 165.1)
		)
		(stroke
			(width 0)
			(type default)
		)
	)
	(polyline
		(pts
			(xy 16.51 180.34) (xy 16.51 190.5)
		)
		(stroke
			(width 0)
			(type default)
		)
	)
	(wire
		(pts
			(xy 118.11 53.34) (xy 146.05 53.34)
		)
		(stroke
			(width 0)
			(type default)
		)
	)
	(wire
		(pts
			(xy 256.54 219.71) (xy 256.54 220.98)
		)
		(stroke
			(width 0)
			(type default)
		)
	)
	(wire
		(pts
			(xy 364.49 226.06) (xy 374.65 226.06)
		)
		(stroke
			(width 0)
			(type default)
		)
	)
	(wire
		(pts
			(xy 102.87 115.57) (xy 99.06 115.57)
		)
		(stroke
			(width 0)
			(type default)
		)
	)
	(wire
		(pts
			(xy 201.93 133.35) (xy 201.93 134.62)
		)
		(stroke
			(width 0)
			(type default)
		)
	)
	(wire
		(pts
			(xy 21.59 50.8) (xy 21.59 53.34)
		)
		(stroke
			(width 0)
			(type default)
		)
	)
	(wire
		(pts
			(xy 309.88 111.76) (xy 330.2 111.76)
		)
		(stroke
			(width 0)
			(type default)
		)
	)
	(wire
		(pts
			(xy 69.85 93.98) (xy 69.85 110.49)
		)
		(stroke
			(width 0)
			(type default)
		)
	)
	(wire
		(pts
			(xy 45.72 250.19) (xy 64.77 250.19)
		)
		(stroke
			(width 0)
			(type default)
		)
	)
	(wire
		(pts
			(xy 176.53 242.57) (xy 190.5 242.57)
		)
		(stroke
			(width 0)
			(type default)
		)
	)
	(wire
		(pts
			(xy 127 247.65) (xy 134.62 247.65)
		)
		(stroke
			(width 0)
			(type default)
		)
	)
	(wire
		(pts
			(xy 265.43 33.02) (xy 265.43 39.37)
		)
		(stroke
			(width 0)
			(type default)
		)
	)
	(wire
		(pts
			(xy 364.49 223.52) (xy 364.49 226.06)
		)
		(stroke
			(width 0)
			(type default)
		)
	)
	(polyline
		(pts
			(xy 201.93 190.5) (xy 201.93 203.2)
		)
		(stroke
			(width 0)
			(type default)
		)
	)
	(polyline
		(pts
			(xy 220.98 246.38) (xy 201.93 246.38)
		)
		(stroke
			(width 0)
			(type default)
		)
	)
	(polyline
		(pts
			(xy 168.91 106.68) (xy 196.85 106.68)
		)
		(stroke
			(width 0)
			(type default)
		)
	)
	(wire
		(pts
			(xy 232.41 59.69) (xy 232.41 58.42)
		)
		(stroke
			(width 0)
			(type default)
		)
	)
	(wire
		(pts
			(xy 180.34 39.37) (xy 180.34 40.64)
		)
		(stroke
			(width 0)
			(type default)
		)
	)
	(wire
		(pts
			(xy 341.63 168.91) (xy 341.63 177.8)
		)
		(stroke
			(width 0)
			(type default)
		)
	)
	(wire
		(pts
			(xy 351.79 212.09) (xy 368.3 212.09)
		)
		(stroke
			(width 0)
			(type default)
		)
	)
	(wire
		(pts
			(xy 135.89 114.3) (xy 135.89 115.57)
		)
		(stroke
			(width 0)
			(type default)
		)
	)
	(wire
		(pts
			(xy 205.74 275.59) (xy 212.09 275.59)
		)
		(stroke
			(width 0)
			(type default)
		)
	)
	(wire
		(pts
			(xy 346.71 114.3) (xy 346.71 111.76)
		)
		(stroke
			(width 0)
			(type default)
		)
	)
	(wire
		(pts
			(xy 204.47 231.14) (xy 220.98 231.14)
		)
		(stroke
			(width 0)
			(type default)
		)
	)
	(polyline
		(pts
			(xy 251.46 95.25) (xy 269.24 95.25)
		)
		(stroke
			(width 0)
			(type default)
		)
	)
	(wire
		(pts
			(xy 144.78 259.08) (xy 151.13 259.08)
		)
		(stroke
			(width 0)
			(type default)
		)
	)
	(wire
		(pts
			(xy 129.54 115.57) (xy 135.89 115.57)
		)
		(stroke
			(width 0)
			(type default)
		)
	)
	(polyline
		(pts
			(xy 120.65 72.39) (xy 72.39 72.39)
		)
		(stroke
			(width 0)
			(type default)
		)
	)
	(wire
		(pts
			(xy 212.09 265.43) (xy 212.09 267.97)
		)
		(stroke
			(width 0)
			(type default)
		)
	)
	(polyline
		(pts
			(xy 43.18 182.88) (xy 22.86 182.88)
		)
		(stroke
			(width 0)
			(type default)
		)
	)
	(wire
		(pts
			(xy 281.94 36.83) (xy 281.94 39.37)
		)
		(stroke
			(width 0)
			(type default)
		)
	)
	(wire
		(pts
			(xy 109.22 273.05) (xy 128.27 273.05)
		)
		(stroke
			(width 0)
			(type default)
		)
	)
	(wire
		(pts
			(xy 234.95 133.35) (xy 245.11 133.35)
		)
		(stroke
			(width 0)
			(type default)
		)
	)
	(wire
		(pts
			(xy 151.13 247.65) (xy 151.13 246.38)
		)
		(stroke
			(width 0)
			(type default)
		)
	)
	(wire
		(pts
			(xy 393.7 214.63) (xy 393.7 217.17)
		)
		(stroke
			(width 0)
			(type default)
		)
	)
	(wire
		(pts
			(xy 49.53 93.98) (xy 59.69 93.98)
		)
		(stroke
			(width 0)
			(type default)
		)
	)
	(wire
		(pts
			(xy 255.27 50.8) (xy 271.78 50.8)
		)
		(stroke
			(width 0)
			(type default)
		)
	)
	(wire
		(pts
			(xy 64.77 229.87) (xy 64.77 234.95)
		)
		(stroke
			(width 0)
			(type default)
		)
	)
	(wire
		(pts
			(xy 119.38 93.98) (xy 119.38 96.52)
		)
		(stroke
			(width 0)
			(type default)
		)
	)
	(wire
		(pts
			(xy 119.38 204.47) (xy 119.38 207.01)
		)
		(stroke
			(width 0)
			(type default)
		)
	)
	(wire
		(pts
			(xy 204.47 231.14) (xy 204.47 234.95)
		)
		(stroke
			(width 0)
			(type default)
		)
	)
	(wire
		(pts
			(xy 99.06 133.35) (xy 119.38 133.35)
		)
		(stroke
			(width 0)
			(type default)
		)
	)
	(wire
		(pts
			(xy 400.05 63.5) (xy 400.05 66.04)
		)
		(stroke
			(width 0)
			(type default)
		)
	)
	(wire
		(pts
			(xy 119.38 140.97) (xy 119.38 143.51)
		)
		(stroke
			(width 0)
			(type default)
		)
	)
	(wire
		(pts
			(xy 388.62 54.61) (xy 388.62 58.42)
		)
		(stroke
			(width 0)
			(type default)
		)
	)
	(wire
		(pts
			(xy 204.47 223.52) (xy 204.47 226.06)
		)
		(stroke
			(width 0)
			(type default)
		)
	)
	(wire
		(pts
			(xy 203.2 186.69) (xy 203.2 187.96)
		)
		(stroke
			(width 0)
			(type default)
		)
	)
	(wire
		(pts
			(xy 102.87 46.99) (xy 102.87 49.53)
		)
		(stroke
			(width 0)
			(type default)
		)
	)
	(wire
		(pts
			(xy 49.53 189.23) (xy 49.53 191.77)
		)
		(stroke
			(width 0)
			(type default)
		)
	)
	(wire
		(pts
			(xy 124.46 24.13) (xy 124.46 25.4)
		)
		(stroke
			(width 0)
			(type default)
		)
	)
	(wire
		(pts
			(xy 350.52 121.92) (xy 350.52 123.19)
		)
		(stroke
			(width 0)
			(type default)
		)
	)
	(polyline
		(pts
			(xy 25.4 91.44) (xy 25.4 92.71)
		)
		(stroke
			(width 0)
			(type default)
		)
	)
	(wire
		(pts
			(xy 110.49 214.63) (xy 119.38 214.63)
		)
		(stroke
			(width 0)
			(type default)
		)
	)
	(wire
		(pts
			(xy 146.05 38.1) (xy 146.05 45.72)
		)
		(stroke
			(width 0)
			(type default)
		)
	)
	(wire
		(pts
			(xy 242.57 48.26) (xy 245.11 48.26)
		)
		(stroke
			(width 0)
			(type default)
		)
	)
	(wire
		(pts
			(xy 242.57 189.23) (xy 242.57 193.04)
		)
		(stroke
			(width 0)
			(type default)
		)
	)
	(wire
		(pts
			(xy 238.76 116.84) (xy 238.76 118.11)
		)
		(stroke
			(width 0)
			(type default)
		)
	)
	(wire
		(pts
			(xy 104.14 46.99) (xy 102.87 46.99)
		)
		(stroke
			(width 0)
			(type default)
		)
	)
	(polyline
		(pts
			(xy 273.05 78.74) (xy 273.05 283.21)
		)
		(stroke
			(width 0)
			(type default)
		)
	)
	(wire
		(pts
			(xy 242.57 200.66) (xy 242.57 203.2)
		)
		(stroke
			(width 0)
			(type default)
		)
	)
	(wire
		(pts
			(xy 388.62 45.72) (xy 392.43 45.72)
		)
		(stroke
			(width 0)
			(type default)
		)
	)
	(wire
		(pts
			(xy 17.78 132.08) (xy 71.12 132.08)
		)
		(stroke
			(width 0)
			(type default)
		)
	)
	(wire
		(pts
			(xy 309.88 111.76) (xy 309.88 114.3)
		)
		(stroke
			(width 0)
			(type default)
		)
	)
	(wire
		(pts
			(xy 121.92 259.08) (xy 121.92 261.62)
		)
		(stroke
			(width 0)
			(type default)
		)
	)
	(wire
		(pts
			(xy 355.6 236.22) (xy 351.79 236.22)
		)
		(stroke
			(width 0)
			(type default)
		)
	)
	(wire
		(pts
			(xy 110.49 190.5) (xy 110.49 193.04)
		)
		(stroke
			(width 0)
			(type default)
		)
	)
	(polyline
		(pts
			(xy 43.18 193.04) (xy 43.18 190.5)
		)
		(stroke
			(width 0)
			(type default)
		)
	)
	(wire
		(pts
			(xy 137.16 132.08) (xy 137.16 133.35)
		)
		(stroke
			(width 0)
			(type default)
		)
	)
	(wire
		(pts
			(xy 384.81 238.76) (xy 384.81 242.57)
		)
		(stroke
			(width 0)
			(type default)
		)
	)
	(wire
		(pts
			(xy 355.6 215.9) (xy 364.49 215.9)
		)
		(stroke
			(width 0)
			(type default)
		)
	)
	(wire
		(pts
			(xy 119.38 125.73) (xy 119.38 127)
		)
		(stroke
			(width 0)
			(type default)
		)
	)
	(polyline
		(pts
			(xy 220.98 233.68) (xy 220.98 246.38)
		)
		(stroke
			(width 0)
			(type default)
		)
	)
	(wire
		(pts
			(xy 146.05 264.16) (xy 146.05 269.24)
		)
		(stroke
			(width 0)
			(type default)
		)
	)
	(polyline
		(pts
			(xy 219.71 190.5) (xy 219.71 203.2)
		)
		(stroke
			(width 0)
			(type default)
		)
	)
	(wire
		(pts
			(xy 245.11 33.02) (xy 255.27 33.02)
		)
		(stroke
			(width 0)
			(type default)
		)
	)
	(polyline
		(pts
			(xy 224.79 201.93) (xy 224.79 209.55)
		)
		(stroke
			(width 0)
			(type default)
		)
	)
	(polyline
		(pts
			(xy 16.51 99.06) (xy 45.72 99.06)
		)
		(stroke
			(width 0)
			(type default)
		)
	)
	(wire
		(pts
			(xy 26.67 41.91) (xy 25.4 41.91)
		)
		(stroke
			(width 0)
			(type default)
		)
	)
	(polyline
		(pts
			(xy 171.45 200.66) (xy 171.45 209.55)
		)
		(stroke
			(width 0)
			(type default)
		)
	)
	(wire
		(pts
			(xy 213.36 58.42) (xy 213.36 59.69)
		)
		(stroke
			(width 0)
			(type default)
		)
	)
	(polyline
		(pts
			(xy 43.18 187.96) (xy 43.18 190.5)
		)
		(stroke
			(width 0)
			(type default)
		)
	)
	(wire
		(pts
			(xy 388.62 45.72) (xy 388.62 40.64)
		)
		(stroke
			(width 0)
			(type default)
		)
	)
	(wire
		(pts
			(xy 184.15 199.39) (xy 189.23 199.39)
		)
		(stroke
			(width 0)
			(type default)
		)
	)
	(wire
		(pts
			(xy 293.37 39.37) (xy 306.07 39.37)
		)
		(stroke
			(width 0)
			(type default)
		)
	)
	(wire
		(pts
			(xy 187.96 158.75) (xy 187.96 160.02)
		)
		(stroke
			(width 0)
			(type default)
		)
	)
	(wire
		(pts
			(xy 384.81 161.29) (xy 391.16 161.29)
		)
		(stroke
			(width 0)
			(type default)
		)
	)
	(wire
		(pts
			(xy 186.69 102.87) (xy 186.69 105.41)
		)
		(stroke
			(width 0)
			(type default)
		)
	)
	(wire
		(pts
			(xy 242.57 200.66) (xy 256.54 200.66)
		)
		(stroke
			(width 0)
			(type default)
		)
	)
	(wire
		(pts
			(xy 106.68 232.41) (xy 106.68 247.65)
		)
		(stroke
			(width 0)
			(type default)
		)
	)
	(polyline
		(pts
			(xy 33.02 182.88) (xy 33.02 193.04)
		)
		(stroke
			(width 0)
			(type default)
		)
	)
	(wire
		(pts
			(xy 363.22 45.72) (xy 363.22 48.26)
		)
		(stroke
			(width 0)
			(type default)
		)
	)
	(wire
		(pts
			(xy 314.96 69.85) (xy 314.96 68.58)
		)
		(stroke
			(width 0)
			(type default)
		)
	)
	(wire
		(pts
			(xy 396.24 153.67) (xy 396.24 149.86)
		)
		(stroke
			(width 0)
			(type default)
		)
	)
	(wire
		(pts
			(xy 302.26 237.49) (xy 302.26 238.76)
		)
		(stroke
			(width 0)
			(type default)
		)
	)
	(wire
		(pts
			(xy 189.23 199.39) (xy 189.23 201.93)
		)
		(stroke
			(width 0)
			(type default)
		)
	)
	(polyline
		(pts
			(xy 224.79 240.03) (xy 251.46 240.03)
		)
		(stroke
			(width 0)
			(type default)
		)
	)
	(wire
		(pts
			(xy 245.11 151.13) (xy 245.11 154.94)
		)
		(stroke
			(width 0)
			(type default)
		)
	)
	(wire
		(pts
			(xy 110.49 125.73) (xy 119.38 125.73)
		)
		(stroke
			(width 0)
			(type default)
		)
	)
	(wire
		(pts
			(xy 49.53 113.03) (xy 49.53 115.57)
		)
		(stroke
			(width 0)
			(type default)
		)
	)
	(wire
		(pts
			(xy 337.82 237.49) (xy 337.82 240.03)
		)
		(stroke
			(width 0)
			(type default)
		)
	)
	(wire
		(pts
			(xy 99.06 201.93) (xy 102.87 201.93)
		)
		(stroke
			(width 0)
			(type default)
		)
	)
	(wire
		(pts
			(xy 110.49 93.98) (xy 118.11 93.98)
		)
		(stroke
			(width 0)
			(type default)
		)
	)
	(polyline
		(pts
			(xy 166.37 172.72) (xy 222.25 172.72)
		)
		(stroke
			(width 0)
			(type default)
		)
	)
	(polyline
		(pts
			(xy 16.51 193.04) (xy 43.18 193.04)
		)
		(stroke
			(width 0)
			(type default)
		)
	)
	(wire
		(pts
			(xy 242.57 212.09) (xy 254 212.09)
		)
		(stroke
			(width 0)
			(type default)
		)
	)
	(wire
		(pts
			(xy 118.11 38.1) (xy 116.84 38.1)
		)
		(stroke
			(width 0)
			(type default)
		)
	)
	(wire
		(pts
			(xy 49.53 209.55) (xy 49.53 212.09)
		)
		(stroke
			(width 0)
			(type default)
		)
	)
	(polyline
		(pts
			(xy 40.64 91.44) (xy 40.64 104.14)
		)
		(stroke
			(width 0)
			(type default)
		)
	)
	(wire
		(pts
			(xy 311.15 161.29) (xy 303.53 161.29)
		)
		(stroke
			(width 0)
			(type default)
		)
	)
	(wire
		(pts
			(xy 361.95 60.96) (xy 373.38 60.96)
		)
		(stroke
			(width 0)
			(type default)
		)
	)
	(wire
		(pts
			(xy 201.93 134.62) (xy 201.93 138.43)
		)
		(stroke
			(width 0)
			(type default)
		)
	)
	(wire
		(pts
			(xy 154.94 24.13) (xy 154.94 25.4)
		)
		(stroke
			(width 0)
			(type default)
		)
	)
	(wire
		(pts
			(xy 252.73 91.44) (xy 252.73 93.98)
		)
		(stroke
			(width 0)
			(type default)
		)
	)
	(polyline
		(pts
			(xy 254 228.6) (xy 254 241.3)
		)
		(stroke
			(width 0)
			(type default)
		)
	)
	(bus
		(pts
			(xy 121.92 46.99) (xy 123.19 48.26)
		)
		(stroke
			(width 0)
			(type default)
		)
	)
	(wire
		(pts
			(xy 49.53 52.07) (xy 55.88 52.07)
		)
		(stroke
			(width 0)
			(type default)
		)
	)
	(bus
		(pts
			(xy 31.75 217.17) (xy 31.75 215.9)
		)
		(stroke
			(width 0)
			(type default)
		)
	)
	(wire
		(pts
			(xy 245.11 140.97) (xy 245.11 143.51)
		)
		(stroke
			(width 0)
			(type default)
		)
	)
	(wire
		(pts
			(xy 231.14 228.6) (xy 242.57 228.6)
		)
		(stroke
			(width 0)
			(type default)
		)
	)
	(wire
		(pts
			(xy 189.23 207.01) (xy 189.23 212.09)
		)
		(stroke
			(width 0)
			(type default)
		)
	)
	(bus
		(pts
			(xy 49.53 144.78) (xy 49.53 142.24)
		)
		(stroke
			(width 0)
			(type default)
		)
	)
	(wire
		(pts
			(xy 306.07 29.21) (xy 314.96 29.21)
		)
		(stroke
			(width 0)
			(type default)
		)
	)
	(wire
		(pts
			(xy 21.59 39.37) (xy 25.4 39.37)
		)
		(stroke
			(width 0)
			(type default)
		)
	)
	(wire
		(pts
			(xy 217.17 31.75) (xy 217.17 33.02)
		)
		(stroke
			(width 0)
			(type default)
		)
	)
	(wire
		(pts
			(xy 119.38 143.51) (xy 119.38 144.78)
		)
		(stroke
			(width 0)
			(type default)
		)
	)
	(wire
		(pts
			(xy 93.98 38.1) (xy 113.03 38.1)
		)
		(stroke
			(width 0)
			(type default)
		)
	)
	(polyline
		(pts
			(xy 274.32 186.69) (xy 407.67 186.69)
		)
		(stroke
			(width 0)
			(type default)
		)
	)
	(polyline
		(pts
			(xy 274.32 139.7) (xy 274.32 186.69)
		)
		(stroke
			(width 0)
			(type default)
		)
	)
	(wire
		(pts
			(xy 110.49 204.47) (xy 119.38 204.47)
		)
		(stroke
			(width 0)
			(type default)
		)
	)
	(wire
		(pts
			(xy 203.2 187.96) (xy 203.2 191.77)
		)
		(stroke
			(width 0)
			(type default)
		)
	)
	(polyline
		(pts
			(xy 274.32 138.43) (xy 407.67 138.43)
		)
		(stroke
			(width 0)
			(type default)
		)
	)
	(wire
		(pts
			(xy 189.23 212.09) (xy 189.23 213.36)
		)
		(stroke
			(width 0)
			(type default)
		)
	)
	(wire
		(pts
			(xy 146.05 269.24) (xy 151.13 269.24)
		)
		(stroke
			(width 0)
			(type default)
		)
	)
	(polyline
		(pts
			(xy 166.37 172.72) (xy 166.37 280.67)
		)
		(stroke
			(width 0)
			(type default)
		)
	)
	(wire
		(pts
			(xy 304.8 66.04) (xy 318.77 66.04)
		)
		(stroke
			(width 0)
			(type default)
		)
	)
	(wire
		(pts
			(xy 355.6 223.52) (xy 355.6 226.06)
		)
		(stroke
			(width 0)
			(type default)
		)
	)
	(wire
		(pts
			(xy 110.49 193.04) (xy 119.38 193.04)
		)
		(stroke
			(width 0)
			(type default)
		)
	)
	(wire
		(pts
			(xy 99.06 138.43) (xy 114.3 138.43)
		)
		(stroke
			(width 0)
			(type default)
		)
	)
	(wire
		(pts
			(xy 281.94 160.02) (xy 281.94 161.29)
		)
		(stroke
			(width 0)
			(type default)
		)
	)
	(wire
		(pts
			(xy 265.43 44.45) (xy 265.43 53.34)
		)
		(stroke
			(width 0)
			(type default)
		)
	)
	(wire
		(pts
			(xy 302.26 228.6) (xy 302.26 229.87)
		)
		(stroke
			(width 0)
			(type default)
		)
	)
	(polyline
		(pts
			(xy 16.51 190.5) (xy 43.18 190.5)
		)
		(stroke
			(width 0)
			(type default)
		)
	)
	(polyline
		(pts
			(xy 71.12 12.7) (xy 71.12 77.47)
		)
		(stroke
			(width 0)
			(type default)
		)
	)
	(bus
		(pts
			(xy 41.91 254) (xy 43.18 254)
		)
		(stroke
			(width 0)
			(type default)
		)
	)
	(wire
		(pts
			(xy 110.49 93.98) (xy 110.49 96.52)
		)
		(stroke
			(width 0)
			(type default)
		)
	)
	(wire
		(pts
			(xy 144.78 264.16) (xy 146.05 264.16)
		)
		(stroke
			(width 0)
			(type default)
		)
	)
	(polyline
		(pts
			(xy 274.32 187.96) (xy 274.32 284.48)
		)
		(stroke
			(width 0)
			(type default)
		)
	)
	(wire
		(pts
			(xy 176.53 232.41) (xy 176.53 234.95)
		)
		(stroke
			(width 0)
			(type default)
		)
	)
	(wire
		(pts
			(xy 201.93 134.62) (xy 217.17 134.62)
		)
		(stroke
			(width 0)
			(type default)
		)
	)
	(wire
		(pts
			(xy 46.99 41.91) (xy 49.53 41.91)
		)
		(stroke
			(width 0)
			(type default)
		)
	)
	(wire
		(pts
			(xy 351.79 166.37) (xy 351.79 165.1)
		)
		(stroke
			(width 0)
			(type default)
		)
	)
	(polyline
		(pts
			(xy 273.05 228.6) (xy 273.05 241.3)
		)
		(stroke
			(width 0)
			(type default)
		)
	)
	(wire
		(pts
			(xy 110.49 64.77) (xy 118.11 64.77)
		)
		(stroke
			(width 0)
			(type default)
		)
	)
	(wire
		(pts
			(xy 293.37 29.21) (xy 281.94 29.21)
		)
		(stroke
			(width 0)
			(type default)
		)
	)
	(wire
		(pts
			(xy 69.85 199.39) (xy 71.12 199.39)
		)
		(stroke
			(width 0)
			(type default)
		)
	)
	(wire
		(pts
			(xy 370.84 45.72) (xy 379.73 45.72)
		)
		(stroke
			(width 0)
			(type default)
		)
	)
	(wire
		(pts
			(xy 309.88 127) (xy 309.88 128.27)
		)
		(stroke
			(width 0)
			(type default)
		)
	)
	(wire
		(pts
			(xy 49.53 201.93) (xy 71.12 201.93)
		)
		(stroke
			(width 0)
			(type default)
		)
	)
	(wire
		(pts
			(xy 99.06 135.89) (xy 102.87 135.89)
		)
		(stroke
			(width 0)
			(type default)
		)
	)
	(wire
		(pts
			(xy 321.31 196.85) (xy 321.31 212.09)
		)
		(stroke
			(width 0)
			(type default)
		)
	)
	(wire
		(pts
			(xy 394.97 161.29) (xy 397.51 161.29)
		)
		(stroke
			(width 0)
			(type default)
		)
	)
	(wire
		(pts
			(xy 69.85 234.95) (xy 69.85 238.76)
		)
		(stroke
			(width 0)
			(type default)
		)
	)
	(wire
		(pts
			(xy 403.86 236.22) (xy 403.86 233.68)
		)
		(stroke
			(width 0)
			(type default)
		)
	)
	(wire
		(pts
			(xy 383.54 228.6) (xy 383.54 233.68)
		)
		(stroke
			(width 0)
			(type default)
		)
	)
	(wire
		(pts
			(xy 101.6 46.99) (xy 102.87 46.99)
		)
		(stroke
			(width 0)
			(type default)
		)
	)
	(wire
		(pts
			(xy 199.39 50.8) (xy 213.36 50.8)
		)
		(stroke
			(width 0)
			(type default)
		)
	)
	(wire
		(pts
			(xy 26.67 39.37) (xy 25.4 39.37)
		)
		(stroke
			(width 0)
			(type default)
		)
	)
	(wire
		(pts
			(xy 350.52 111.76) (xy 363.22 111.76)
		)
		(stroke
			(width 0)
			(type default)
		)
	)
	(wire
		(pts
			(xy 233.68 105.41) (xy 238.76 105.41)
		)
		(stroke
			(width 0)
			(type default)
		)
	)
	(polyline
		(pts
			(xy 199.39 95.25) (xy 217.17 95.25)
		)
		(stroke
			(width 0)
			(type default)
		)
	)
	(wire
		(pts
			(xy 59.69 100.33) (xy 59.69 102.87)
		)
		(stroke
			(width 0)
			(type default)
		)
	)
	(polyline
		(pts
			(xy 43.18 187.96) (xy 43.18 180.34)
		)
		(stroke
			(width 0)
			(type default)
		)
	)
	(wire
		(pts
			(xy 388.62 54.61) (xy 400.05 54.61)
		)
		(stroke
			(width 0)
			(type default)
		)
	)
	(wire
		(pts
			(xy 110.49 115.57) (xy 119.38 115.57)
		)
		(stroke
			(width 0)
			(type default)
		)
	)
	(wire
		(pts
			(xy 201.93 143.51) (xy 201.93 146.05)
		)
		(stroke
			(width 0)
			(type default)
		)
	)
	(wire
		(pts
			(xy 139.7 247.65) (xy 151.13 247.65)
		)
		(stroke
			(width 0)
			(type default)
		)
	)
	(polyline
		(pts
			(xy 196.85 147.32) (xy 196.85 156.21)
		)
		(stroke
			(width 0)
			(type default)
		)
	)
	(polyline
		(pts
			(xy 273.05 12.7) (xy 273.05 77.47)
		)
		(stroke
			(width 0)
			(type default)
		)
	)
	(polyline
		(pts
			(xy 199.39 95.25) (xy 199.39 107.95)
		)
		(stroke
			(width 0)
			(type default)
		)
	)
	(wire
		(pts
			(xy 59.69 93.98) (xy 59.69 95.25)
		)
		(stroke
			(width 0)
			(type default)
		)
	)
	(wire
		(pts
			(xy 355.6 236.22) (xy 355.6 238.76)
		)
		(stroke
			(width 0)
			(type default)
		)
	)
	(wire
		(pts
			(xy 256.54 187.96) (xy 267.97 187.96)
		)
		(stroke
			(width 0)
			(type default)
		)
	)
	(wire
		(pts
			(xy 176.53 240.03) (xy 176.53 242.57)
		)
		(stroke
			(width 0)
			(type default)
		)
	)
	(wire
		(pts
			(xy 140.97 40.64) (xy 139.7 40.64)
		)
		(stroke
			(width 0)
			(type default)
		)
	)
	(bus
		(pts
			(xy 92.71 35.56) (xy 93.98 35.56)
		)
		(stroke
			(width 0)
			(type default)
		)
	)
	(wire
		(pts
			(xy 110.49 62.23) (xy 118.11 62.23)
		)
		(stroke
			(width 0)
			(type default)
		)
	)
	(wire
		(pts
			(xy 189.23 199.39) (xy 203.2 199.39)
		)
		(stroke
			(width 0)
			(type default)
		)
	)
	(polyline
		(pts
			(xy 222.25 172.72) (xy 222.25 280.67)
		)
		(stroke
			(width 0)
			(type default)
		)
	)
	(polyline
		(pts
			(xy 201.93 233.68) (xy 220.98 233.68)
		)
		(stroke
			(width 0)
			(type default)
		)
	)
	(wire
		(pts
			(xy 386.08 203.2) (xy 386.08 215.9)
		)
		(stroke
			(width 0)
			(type default)
		)
	)
	(wire
		(pts
			(xy 363.22 53.34) (xy 363.22 55.88)
		)
		(stroke
			(width 0)
			(type default)
		)
	)
	(wire
		(pts
			(xy 110.49 152.4) (xy 119.38 152.4)
		)
		(stroke
			(width 0)
			(type default)
		)
	)
	(wire
		(pts
			(xy 200.66 91.44) (xy 200.66 93.98)
		)
		(stroke
			(width 0)
			(type default)
		)
	)
	(wire
		(pts
			(xy 388.62 63.5) (xy 388.62 66.04)
		)
		(stroke
			(width 0)
			(type default)
		)
	)
	(wire
		(pts
			(xy 157.48 31.75) (xy 161.29 31.75)
		)
		(stroke
			(width 0)
			(type default)
		)
	)
	(bus
		(pts
			(xy 123.19 48.26) (xy 124.46 48.26)
		)
		(stroke
			(width 0)
			(type default)
		)
	)
	(polyline
		(pts
			(xy 25.4 92.71) (xy 25.4 104.14)
		)
		(stroke
			(width 0)
			(type default)
		)
	)
	(polyline
		(pts
			(xy 172.72 243.84) (xy 172.72 252.73)
		)
		(stroke
			(width 0)
			(type default)
		)
	)
	(wire
		(pts
			(xy 256.54 187.96) (xy 256.54 193.04)
		)
		(stroke
			(width 0)
			(type default)
		)
	)
	(wire
		(pts
			(xy 142.24 62.23) (xy 160.02 62.23)
		)
		(stroke
			(width 0)
			(type default)
		)
	)
	(wire
		(pts
			(xy 389.89 172.72) (xy 389.89 165.1)
		)
		(stroke
			(width 0)
			(type default)
		)
	)
	(wire
		(pts
			(xy 240.03 143.51) (xy 245.11 143.51)
		)
		(stroke
			(width 0)
			(type default)
		)
	)
	(wire
		(pts
			(xy 152.4 38.1) (xy 153.67 38.1)
		)
		(stroke
			(width 0)
			(type default)
		)
	)
	(polyline
		(pts
			(xy 274.32 95.25) (xy 407.67 95.25)
		)
		(stroke
			(width 0)
			(type default)
		)
	)
	(polyline
		(pts
			(xy 185.42 36.83) (xy 185.42 77.47)
		)
		(stroke
			(width 0)
			(type default)
		)
	)
	(polyline
		(pts
			(xy 189.23 48.26) (xy 189.23 66.04)
		)
		(stroke
			(width 0)
			(type default)
		)
	)
	(polyline
		(pts
			(xy 217.17 95.25) (xy 217.17 107.95)
		)
		(stroke
			(width 0)
			(type default)
		)
	)
	(polyline
		(pts
			(xy 274.32 12.7) (xy 274.32 95.25)
		)
		(stroke
			(width 0)
			(type default)
		)
	)
	(wire
		(pts
			(xy 345.44 111.76) (xy 346.71 111.76)
		)
		(stroke
			(width 0)
			(type default)
		)
	)
	(polyline
		(pts
			(xy 201.93 190.5) (xy 219.71 190.5)
		)
		(stroke
			(width 0)
			(type default)
		)
	)
	(wire
		(pts
			(xy 403.86 228.6) (xy 403.86 233.68)
		)
		(stroke
			(width 0)
			(type default)
		)
	)
	(label "FB7"
		(at 102.87 224.79 180)
		(effects
			(font
				(size 1.27 1.27)
			)
			(justify right bottom)
		)
	)
	(label "FB7"
		(at 237.49 200.66 0)
		(effects
			(font
				(size 1.27 1.27)
			)
			(justify left bottom)
		)
	)
	(label "VDDR_VTT"
		(at 355.6 215.9 0)
		(effects
			(font
				(size 1.27 1.27)
			)
			(justify left bottom)
		)
	)
	(label "1V35_local"
		(at 231.14 228.6 0)
		(effects
			(font
				(size 1.27 1.27)
			)
			(justify left bottom)
		)
	)
	(label "1V0_REG"
		(at 350.52 53.34 180)
		(effects
			(font
				(size 1.27 1.27)
			)
			(justify right bottom)
		)
	)
	(label "1V0_FB"
		(at 341.63 60.96 0)
		(effects
			(font
				(size 1.27 1.27)
			)
			(justify left bottom)
		)
	)
	(label "SENSE_1V35_P"
		(at 270.51 226.06 180)
		(effects
			(font
				(size 1.27 1.27)
			)
			(justify right bottom)
		)
	)
	(label "QDCDC2_GPIO"
		(at 50.8 229.87 0)
		(effects
			(font
				(size 1.27 1.27)
			)
			(justify left bottom)
		)
	)
	(label "EN2"
		(at 67.31 120.65 0)
		(effects
			(font
				(size 1.27 1.27)
			)
			(justify left bottom)
		)
	)
	(label "3V3_local_2"
		(at 106.68 204.47 0)
		(effects
			(font
				(size 1.27 1.27)
			)
			(justify left bottom)
		)
	)
	(label "FB6"
		(at 102.87 217.17 180)
		(effects
			(font
				(size 1.27 1.27)
			)
			(justify right bottom)
		)
	)
	(label "+0V675_EN"
		(at 311.15 218.44 0)
		(effects
			(font
				(size 1.27 1.27)
			)
			(justify left bottom)
		)
	)
	(label "SW1"
		(at 205.74 265.43 0)
		(effects
			(font
				(size 1.27 1.27)
			)
			(justify left bottom)
		)
	)
	(label "1V2_local"
		(at 107.95 133.35 0)
		(effects
			(font
				(size 1.27 1.27)
			)
			(justify left bottom)
		)
	)
	(label "I2C.SDA"
		(at 33.02 218.44 0)
		(effects
			(font
				(size 1.27 1.27)
			)
			(justify left bottom)
		)
	)
	(label "VDDR_PGOOD"
		(at 368.3 212.09 180)
		(effects
			(font
				(size 1.27 1.27)
			)
			(justify right bottom)
		)
	)
	(label "PB_CTRL_OUT"
		(at 139.7 35.56 0)
		(effects
			(font
				(size 1.27 1.27)
			)
			(justify left bottom)
		)
	)
	(label "1V85_VIN"
		(at 302.26 161.29 0)
		(effects
			(font
				(size 1.27 1.27)
			)
			(justify left bottom)
		)
	)
	(label "SUP_MCU.PG_3V3"
		(at 62.23 250.19 180)
		(effects
			(font
				(size 1.27 1.27)
			)
			(justify right bottom)
		)
	)
	(label "SW1"
		(at 102.87 201.93 180)
		(effects
			(font
				(size 1.27 1.27)
			)
			(justify right bottom)
		)
	)
	(label "EN3"
		(at 271.78 53.34 180)
		(effects
			(font
				(size 1.27 1.27)
			)
			(justify right bottom)
		)
	)
	(label "SUP_MCU.PG_VCCINT"
		(at 314.96 59.69 180)
		(effects
			(font
				(size 1.27 1.27)
			)
			(justify right bottom)
		)
	)
	(label "FB4"
		(at 240.03 143.51 0)
		(effects
			(font
				(size 1.27 1.27)
			)
			(justify left bottom)
		)
	)
	(label "FB3"
		(at 102.87 135.89 180)
		(effects
			(font
				(size 1.27 1.27)
			)
			(justify right bottom)
		)
	)
	(label "EN3"
		(at 67.31 209.55 0)
		(effects
			(font
				(size 1.27 1.27)
			)
			(justify left bottom)
		)
	)
	(label "1V7_local"
		(at 101.6 143.51 0)
		(effects
			(font
				(size 1.27 1.27)
			)
			(justify left bottom)
		)
	)
	(label "1V8_local"
		(at 177.8 133.35 0)
		(effects
			(font
				(size 1.27 1.27)
			)
			(justify left bottom)
		)
	)
	(label "FB8"
		(at 102.87 234.95 180)
		(effects
			(font
				(size 1.27 1.27)
			)
			(justify right bottom)
		)
	)
	(label "FB5"
		(at 173.99 232.41 0)
		(effects
			(font
				(size 1.27 1.27)
			)
			(justify left bottom)
		)
	)
	(label "PB_CTRL.~{PB_CTRL_INT}"
		(at 123.19 45.72 0)
		(effects
			(font
				(size 1.27 1.27)
			)
			(justify left bottom)
		)
	)
	(label "SENSE_1V0_P"
		(at 217.17 93.98 180)
		(effects
			(font
				(size 1.27 1.27)
			)
			(justify right bottom)
		)
	)
	(label "SEQ_EN"
		(at 214.63 50.8 0)
		(effects
			(font
				(size 1.27 1.27)
			)
			(justify left bottom)
		)
	)
	(label "I2C.SCL"
		(at 304.8 66.04 0)
		(effects
			(font
				(size 1.27 1.27)
			)
			(justify left bottom)
		)
	)
	(label "MGTAVTT_OUT"
		(at 347.98 111.76 0)
		(effects
			(font
				(size 1.27 1.27)
			)
			(justify left bottom)
		)
	)
	(label "EN2"
		(at 271.78 50.8 180)
		(effects
			(font
				(size 1.27 1.27)
			)
			(justify right bottom)
		)
	)
	(label "PB_CTRL.~{PB_CTRL_CLR}"
		(at 93.98 38.1 0)
		(effects
			(font
				(size 1.27 1.27)
			)
			(justify left bottom)
		)
	)
	(label "1V0_REG"
		(at 370.84 45.72 0)
		(effects
			(font
				(size 1.27 1.27)
			)
			(justify left bottom)
		)
	)
	(label "EN1"
		(at 312.42 50.8 0)
		(effects
			(font
				(size 1.27 1.27)
			)
			(justify left bottom)
		)
	)
	(label "SW2"
		(at 102.87 214.63 180)
		(effects
			(font
				(size 1.27 1.27)
			)
			(justify right bottom)
		)
	)
	(label "FB4"
		(at 102.87 146.05 180)
		(effects
			(font
				(size 1.27 1.27)
			)
			(justify right bottom)
		)
	)
	(label "3V3_local_2"
		(at 179.07 229.87 0)
		(effects
			(font
				(size 1.27 1.27)
			)
			(justify left bottom)
		)
	)
	(label "VDDR_VRI"
		(at 314.96 229.87 0)
		(effects
			(font
				(size 1.27 1.27)
			)
			(justify left bottom)
		)
	)
	(label "I2C.SDA"
		(at 304.8 63.5 0)
		(effects
			(font
				(size 1.27 1.27)
			)
			(justify left bottom)
		)
	)
	(label "SUP_MCU.PG_1V2"
		(at 67.31 143.51 180)
		(effects
			(font
				(size 1.27 1.27)
			)
			(justify right bottom)
		)
	)
	(label "3V3_local"
		(at 100.33 182.88 0)
		(effects
			(font
				(size 1.27 1.27)
			)
			(justify left bottom)
		)
	)
	(label "SENSE_1V0_N"
		(at 203.2 116.84 180)
		(effects
			(font
				(size 1.27 1.27)
			)
			(justify right bottom)
		)
	)
	(label "SENSE_1V8_N"
		(at 203.2 158.75 180)
		(effects
			(font
				(size 1.27 1.27)
			)
			(justify right bottom)
		)
	)
	(label "SENSE_1V35_N"
		(at 256.54 250.19 180)
		(effects
			(font
				(size 1.27 1.27)
			)
			(justify right bottom)
		)
	)
	(label "1V8_local"
		(at 107.95 115.57 0)
		(effects
			(font
				(size 1.27 1.27)
			)
			(justify left bottom)
		)
	)
	(label "3V3_local"
		(at 180.34 189.23 0)
		(effects
			(font
				(size 1.27 1.27)
			)
			(justify left bottom)
		)
	)
	(label "MGTAVCC_local"
		(at 100.33 93.98 0)
		(effects
			(font
				(size 1.27 1.27)
			)
			(justify left bottom)
		)
	)
	(label "1V0_SS"
		(at 341.63 68.58 0)
		(effects
			(font
				(size 1.27 1.27)
			)
			(justify left bottom)
		)
	)
	(label "~{PB_CTRL_IN}"
		(at 104.14 40.64 0)
		(effects
			(font
				(size 1.27 1.27)
			)
			(justify left bottom)
		)
	)
	(label "I2C.QDCDC2_SCL"
		(at 33.02 220.98 0)
		(effects
			(font
				(size 1.27 1.27)
			)
			(justify left bottom)
		)
	)
	(label "QDCDC1_VCC"
		(at 57.15 113.03 0)
		(effects
			(font
				(size 1.27 1.27)
			)
			(justify left bottom)
		)
	)
	(label "FB2"
		(at 102.87 128.27 180)
		(effects
			(font
				(size 1.27 1.27)
			)
			(justify right bottom)
		)
	)
	(label "FB1"
		(at 181.61 105.41 0)
		(effects
			(font
				(size 1.27 1.27)
			)
			(justify left bottom)
		)
	)
	(label "1V35_local"
		(at 113.03 247.65 0)
		(effects
			(font
				(size 1.27 1.27)
			)
			(justify left bottom)
		)
	)
	(label "FB5"
		(at 102.87 204.47 180)
		(effects
			(font
				(size 1.27 1.27)
			)
			(justify right bottom)
		)
	)
	(label "1V0_BS"
		(at 328.93 33.02 270)
		(effects
			(font
				(size 1.27 1.27)
			)
			(justify right bottom)
		)
	)
	(label "1V7"
		(at 135.89 152.4 180)
		(effects
			(font
				(size 1.27 1.27)
			)
			(justify right bottom)
		)
	)
	(label "MGTAVCC_local"
		(at 172.72 93.98 0)
		(effects
			(font
				(size 1.27 1.27)
			)
			(justify left bottom)
		)
	)
	(label "SENSE_1V8_P"
		(at 217.17 134.62 180)
		(effects
			(font
				(size 1.27 1.27)
			)
			(justify right bottom)
		)
	)
	(label "5V_local"
		(at 100.33 222.25 0)
		(effects
			(font
				(size 1.27 1.27)
			)
			(justify left bottom)
		)
	)
	(label "1V2_local"
		(at 229.87 93.98 0)
		(effects
			(font
				(size 1.27 1.27)
			)
			(justify left bottom)
		)
	)
	(label "5V_local"
		(at 233.68 189.23 0)
		(effects
			(font
				(size 1.27 1.27)
			)
			(justify left bottom)
		)
	)
	(label "FB6"
		(at 171.45 242.57 0)
		(effects
			(font
				(size 1.27 1.27)
			)
			(justify left bottom)
		)
	)
	(label "QDCDC2_VCC"
		(at 36.83 201.93 0)
		(effects
			(font
				(size 1.27 1.27)
			)
			(justify left bottom)
		)
	)
	(label "SENSE_5V_N"
		(at 254 212.09 180)
		(effects
			(font
				(size 1.27 1.27)
			)
			(justify right bottom)
		)
	)
	(label "+0V675_EN"
		(at 373.38 236.22 0)
		(effects
			(font
				(size 1.27 1.27)
			)
			(justify left bottom)
		)
	)
	(label "EN1"
		(at 271.78 48.26 180)
		(effects
			(font
				(size 1.27 1.27)
			)
			(justify right bottom)
		)
	)
	(label "1V0_VCC"
		(at 281.94 53.34 0)
		(effects
			(font
				(size 1.27 1.27)
			)
			(justify left bottom)
		)
	)
	(label "SUP_MCU.PG_1V8"
		(at 67.31 140.97 180)
		(effects
			(font
				(size 1.27 1.27)
			)
			(justify right bottom)
		)
	)
	(label "SENSE_1V2_N"
		(at 255.27 116.84 180)
		(effects
			(font
				(size 1.27 1.27)
			)
			(justify right bottom)
		)
	)
	(label "SENSE_3V3_2_N"
		(at 207.01 255.27 180)
		(effects
			(font
				(size 1.27 1.27)
			)
			(justify right bottom)
		)
	)
	(label "FB1"
		(at 102.87 115.57 180)
		(effects
			(font
				(size 1.27 1.27)
			)
			(justify right bottom)
		)
	)
	(label "MGTAVTT_ILIM"
		(at 317.5 116.84 0)
		(effects
			(font
				(size 1.27 1.27)
			)
			(justify left bottom)
		)
	)
	(label "1V0_SW"
		(at 341.63 33.02 270)
		(effects
			(font
				(size 1.27 1.27)
			)
			(justify right bottom)
		)
	)
	(label "SENSE_3V3_1_P"
		(at 219.71 187.96 180)
		(effects
			(font
				(size 1.27 1.27)
			)
			(justify right bottom)
		)
	)
	(label "I2C.SDA"
		(at 19.05 129.54 0)
		(effects
			(font
				(size 1.27 1.27)
			)
			(justify left bottom)
		)
	)
	(label "1V7"
		(at 304.8 111.76 0)
		(effects
			(font
				(size 1.27 1.27)
			)
			(justify left bottom)
		)
	)
	(label "ON{slash}OFF"
		(at 189.23 35.56 180)
		(effects
			(font
				(size 1.27 1.27)
			)
			(justify right bottom)
		)
	)
	(label "SENSE_3V3_1_N"
		(at 205.74 212.09 180)
		(effects
			(font
				(size 1.27 1.27)
			)
			(justify right bottom)
		)
	)
	(label "FB2"
		(at 181.61 146.05 0)
		(effects
			(font
				(size 1.27 1.27)
			)
			(justify left bottom)
		)
	)
	(label "SENSE_5V_P"
		(at 267.97 187.96 180)
		(effects
			(font
				(size 1.27 1.27)
			)
			(justify right bottom)
		)
	)
	(label "1V85_OUT"
		(at 341.63 153.67 0)
		(effects
			(font
				(size 1.27 1.27)
			)
			(justify left bottom)
		)
	)
	(label "SENSE_3V3_2_P"
		(at 220.98 231.14 180)
		(effects
			(font
				(size 1.27 1.27)
			)
			(justify right bottom)
		)
	)
	(label "FB3"
		(at 233.68 105.41 0)
		(effects
			(font
				(size 1.27 1.27)
			)
			(justify left bottom)
		)
	)
	(label "SW2"
		(at 205.74 275.59 0)
		(effects
			(font
				(size 1.27 1.27)
			)
			(justify left bottom)
		)
	)
	(label "1V7_local"
		(at 234.95 133.35 0)
		(effects
			(font
				(size 1.27 1.27)
			)
			(justify left bottom)
		)
	)
	(label "FB8"
		(at 237.49 238.76 0)
		(effects
			(font
				(size 1.27 1.27)
			)
			(justify left bottom)
		)
	)
	(label "SUP_MCU.SW_STATE"
		(at 96.52 35.56 0)
		(effects
			(font
				(size 1.27 1.27)
			)
			(justify left bottom)
		)
	)
	(label "FB5"
		(at 184.15 199.39 0)
		(effects
			(font
				(size 1.27 1.27)
			)
			(justify left bottom)
		)
	)
	(label "PB_CTRL.VDDR_EN"
		(at 110.49 273.05 0)
		(effects
			(font
				(size 1.27 1.27)
			)
			(justify left bottom)
		)
	)
	(label "SENSE_1V2_P"
		(at 269.24 93.98 180)
		(effects
			(font
				(size 1.27 1.27)
			)
			(justify right bottom)
		)
	)
	(label "I2C.QDCDC1_SCL"
		(at 19.05 132.08 0)
		(effects
			(font
				(size 1.27 1.27)
			)
			(justify left bottom)
		)
	)
	(label "PB_CTRL_OE"
		(at 146.05 62.23 0)
		(effects
			(font
				(size 1.27 1.27)
			)
			(justify left bottom)
		)
	)
	(global_label "VREFN"
		(shape input)
		(at 397.51 165.1 0)
		(fields_autoplaced yes)
		(effects
			(font
				(size 1.27 1.27)
			)
			(justify left)
		)
		(property "Intersheetrefs" "${INTERSHEET_REFS}"
			(at 405.8498 165.0206 0)
			(effects
				(font
					(size 1.27 1.27)
				)
				(justify left)
				(hide yes)
			)
		)
	)
	(global_label "VREFP"
		(shape input)
		(at 397.51 161.29 0)
		(fields_autoplaced yes)
		(effects
			(font
				(size 1.27 1.27)
			)
			(justify left)
		)
		(property "Intersheetrefs" "${INTERSHEET_REFS}"
			(at 405.7893 161.2106 0)
			(effects
				(font
					(size 1.27 1.27)
				)
				(justify left)
				(hide yes)
			)
		)
	)
	(hierarchical_label "PB_CTRL{PB-CTRL}"
		(shape bidirectional)
		(at 91.44 38.1 180)
		(effects
			(font
				(size 1.27 1.27)
			)
			(justify right)
		)
	)
	(hierarchical_label "I2C{I2C}"
		(shape bidirectional)
		(at 34.29 214.63 0)
		(effects
			(font
				(size 1.27 1.27)
			)
			(justify left)
		)
	)
	(hierarchical_label "PB_CTRL{PB-CTRL}"
		(shape bidirectional)
		(at 124.46 48.26 0)
		(effects
			(font
				(size 1.27 1.27)
			)
			(justify left)
		)
	)
	(hierarchical_label "SUP_MCU{SUP-MCU}"
		(shape bidirectional)
		(at 92.71 35.56 180)
		(effects
			(font
				(size 1.27 1.27)
			)
			(justify right)
		)
	)
	(hierarchical_label "I2C{I2C}"
		(shape bidirectional)
		(at 24.13 121.92 0)
		(effects
			(font
				(size 1.27 1.27)
			)
			(justify left)
		)
	)
	(hierarchical_label "POE_DC"
		(shape input)
		(at 88.9 62.23 180)
		(effects
			(font
				(size 1.27 1.27)
			)
			(justify right)
		)
	)
	(hierarchical_label "SUP_MCU{SUP-MCU}"
		(shape bidirectional)
		(at 46.99 147.32 180)
		(effects
			(font
				(size 1.27 1.27)
			)
			(justify right)
		)
	)
	(hierarchical_label "SUP_MCU{SUP-MCU}"
		(shape bidirectional)
		(at 297.18 71.12 180)
		(effects
			(font
				(size 1.27 1.27)
			)
			(justify right)
		)
	)
	(hierarchical_label "PB_CTRL{PB-CTRL}"
		(shape bidirectional)
		(at 106.68 273.05 180)
		(effects
			(font
				(size 1.27 1.27)
			)
			(justify right)
		)
	)
	(hierarchical_label "SUP_MCU{SUP-MCU}"
		(shape bidirectional)
		(at 41.91 254 180)
		(effects
			(font
				(size 1.27 1.27)
			)
			(justify right)
		)
	)
	(hierarchical_label "I2C{I2C}"
		(shape bidirectional)
		(at 297.18 77.47 180)
		(effects
			(font
				(size 1.27 1.27)
			)
			(justify right)
		)
	)
	(symbol
		(lib_id "antmicroCapacitors0402:C_1u_0402")
		(at 303.53 171.45 90)
		(unit 1)
		(exclude_from_sim no)
		(in_bom yes)
		(on_board yes)
		(dnp no)
		(property "Reference" "C346"
			(at 304.165 167.005 90)
			(effects
				(font
					(size 1.27 1.27)
				)
				(justify right)
			)
		)
		(property "Value" "C_1u_0402"
			(at 313.69 151.13 0)
			(effects
				(font
					(size 1.27 1.27)
					(thickness 0.15)
				)
				(justify left bottom)
				(hide yes)
			)
		)
		(property "Footprint" "antmicro-footprints:C_0402_1005Metric"
			(at 316.23 151.13 0)
			(effects
				(font
					(size 1.27 1.27)
					(thickness 0.15)
				)
				(justify left bottom)
				(hide yes)
			)
		)
		(property "Datasheet" "https://product.tdk.com/en/search/capacitor/ceramic/mlcc/info?part_no=C1005X6S1A105K050BC"
			(at 318.77 151.13 0)
			(effects
				(font
					(size 1.27 1.27)
					(thickness 0.15)
				)
				(justify left bottom)
				(hide yes)
			)
		)
		(property "Description" ""
			(at 303.53 171.45 0)
			(effects
				(font
					(size 1.27 1.27)
				)
			)
		)
		(property "Manufacturer" "TDK"
			(at 323.85 151.13 0)
			(effects
				(font
					(size 1.27 1.27)
					(thickness 0.15)
				)
				(justify left bottom)
				(hide yes)
			)
		)
		(property "MPN" "C1005X6S1A105K050BC"
			(at 321.31 151.13 0)
			(effects
				(font
					(size 1.27 1.27)
					(thickness 0.15)
				)
				(justify left bottom)
				(hide yes)
			)
		)
		(property "Val" "1u"
			(at 304.165 170.815 90)
			(effects
				(font
					(size 1.27 1.27)
					(thickness 0.15)
				)
				(justify right)
			)
		)
		(property "License" "Apache-2.0"
			(at 326.39 151.13 0)
			(effects
				(font
					(size 1.27 1.27)
					(thickness 0.15)
				)
				(justify left bottom)
				(hide yes)
			)
		)
		(property "Author" "Antmicro"
			(at 328.93 151.13 0)
			(effects
				(font
					(size 1.27 1.27)
					(thickness 0.15)
				)
				(justify left bottom)
				(hide yes)
			)
		)
		(property "Voltage" ""
			(at 331.47 151.13 0)
			(effects
				(font
					(size 1.27 1.27)
				)
				(justify left bottom)
				(hide yes)
			)
		)
		(property "Dielectric" ""
			(at 334.01 151.13 0)
			(effects
				(font
					(size 1.27 1.27)
				)
				(justify left bottom)
				(hide yes)
			)
		)
		(pin "1"
		)
		(pin "2"
		)
		(instances
			(project "k410t-devboard"
				(path ""
					(reference "C346")
					(unit 1)
				)
			)
		)
	)
	(symbol
		(lib_id "k410t-devboard:Net-Tie_2")
		(at 187.96 163.83 90)
		(unit 1)
		(exclude_from_sim no)
		(in_bom yes)
		(on_board yes)
		(dnp no)
		(fields_autoplaced yes)
		(property "Reference" "NT35"
			(at 186.69 163.83 0)
			(effects
				(font
					(size 1.27 1.27)
				)
				(hide yes)
			)
		)
		(property "Value" "Net-Tie_2"
			(at 189.865 161.9249 90)
			(effects
				(font
					(size 1.27 1.27)
					(thickness 0.15)
				)
				(justify right)
				(hide yes)
			)
		)
		(property "Footprint" "antmicro-footprints:NetTie-2_SMD_Pad0.127mm"
			(at 193.04 142.24 0)
			(effects
				(font
					(size 1.27 1.27)
					(thickness 0.15)
				)
				(justify left bottom)
				(hide yes)
			)
		)
		(property "Datasheet" ""
			(at 195.58 142.24 0)
			(effects
				(font
					(size 1.27 1.27)
					(thickness 0.15)
				)
				(justify left bottom)
				(hide yes)
			)
		)
		(property "Description" ""
			(at 187.96 163.83 0)
			(effects
				(font
					(size 1.27 1.27)
				)
			)
		)
		(property "MPN" ""
			(at 196.85 142.24 0)
			(effects
				(font
					(size 1.27 1.27)
				)
				(justify left)
				(hide yes)
			)
		)
		(property "Manufacturer" ""
			(at 199.39 142.24 0)
			(effects
				(font
					(size 1.27 1.27)
				)
				(justify left)
				(hide yes)
			)
		)
		(property "Author" "Antmicro"
			(at 203.2 142.24 0)
			(effects
				(font
					(size 1.27 1.27)
					(thickness 0.15)
				)
				(justify left bottom)
				(hide yes)
			)
		)
		(property "License" "Apache-2.0"
			(at 205.74 142.24 0)
			(effects
				(font
					(size 1.27 1.27)
					(thickness 0.15)
				)
				(justify left bottom)
				(hide yes)
			)
		)
		(pin "1"
		)
		(pin "2"
		)
		(instances
			(project "k410t-devboard"
				(path ""
					(reference "NT35")
					(unit 1)
				)
			)
		)
	)
	(symbol
		(lib_id "antmicroCapacitors0402:C_100n_0402")
		(at 154.94 24.13 90)
		(unit 1)
		(exclude_from_sim no)
		(in_bom yes)
		(on_board yes)
		(dnp no)
		(property "Reference" "C337"
			(at 148.59 20.32 90)
			(effects
				(font
					(size 1.27 1.27)
				)
				(justify right)
			)
		)
		(property "Value" "C_100n_0402"
			(at 165.1 3.81 0)
			(effects
				(font
					(size 1.27 1.27)
					(thickness 0.15)
				)
				(justify left bottom)
				(hide yes)
			)
		)
		(property "Footprint" "antmicro-footprints:C_0402_1005Metric"
			(at 167.64 3.81 0)
			(effects
				(font
					(size 1.27 1.27)
					(thickness 0.15)
				)
				(justify left bottom)
				(hide yes)
			)
		)
		(property "Datasheet" "https://www.murata.com/products/productdetail?partno=GRM155R61H104KE14%23"
			(at 170.18 3.81 0)
			(effects
				(font
					(size 1.27 1.27)
					(thickness 0.15)
				)
				(justify left bottom)
				(hide yes)
			)
		)
		(property "Description" ""
			(at 154.94 24.13 0)
			(effects
				(font
					(size 1.27 1.27)
				)
			)
		)
		(property "Manufacturer" "Murata"
			(at 175.26 3.81 0)
			(effects
				(font
					(size 1.27 1.27)
					(thickness 0.15)
				)
				(justify left bottom)
				(hide yes)
			)
		)
		(property "MPN" "GRM155R61H104KE14D"
			(at 172.72 3.81 0)
			(effects
				(font
					(size 1.27 1.27)
					(thickness 0.15)
				)
				(justify left bottom)
				(hide yes)
			)
		)
		(property "Val" "100n"
			(at 148.59 22.86 90)
			(effects
				(font
					(size 1.27 1.27)
					(thickness 0.15)
				)
				(justify right)
			)
		)
		(property "License" "Apache-2.0"
			(at 177.8 3.81 0)
			(effects
				(font
					(size 1.27 1.27)
					(thickness 0.15)
				)
				(justify left bottom)
				(hide yes)
			)
		)
		(property "Author" "Antmicro"
			(at 180.34 3.81 0)
			(effects
				(font
					(size 1.27 1.27)
					(thickness 0.15)
				)
				(justify left bottom)
				(hide yes)
			)
		)
		(property "Voltage" "50V"
			(at 182.88 3.81 0)
			(effects
				(font
					(size 1.27 1.27)
				)
				(justify left bottom)
				(hide yes)
			)
		)
		(property "Dielectric" "X5R"
			(at 185.42 3.81 0)
			(effects
				(font
					(size 1.27 1.27)
				)
				(justify left bottom)
				(hide yes)
			)
		)
		(pin "1"
		)
		(pin "2"
		)
		(instances
			(project "k410t-devboard"
				(path ""
					(reference "C337")
					(unit 1)
				)
			)
		)
	)
	(symbol
		(lib_id "antmicropower:GND")
		(at 290.83 231.14 0)
		(unit 1)
		(exclude_from_sim no)
		(in_bom yes)
		(on_board yes)
		(dnp no)
		(fields_autoplaced yes)
		(property "Reference" "#PWR0415"
			(at 290.83 237.49 0)
			(effects
				(font
					(size 1.27 1.27)
				)
				(hide yes)
			)
		)
		(property "Value" "GND"
			(at 290.83 234.95 0)
			(effects
				(font
					(size 1.27 1.27)
				)
			)
		)
		(property "Footprint" ""
			(at 299.72 238.76 0)
			(effects
				(font
					(size 1.27 1.27)
					(thickness 0.15)
				)
				(justify left bottom)
				(hide yes)
			)
		)
		(property "Datasheet" ""
			(at 299.72 243.84 0)
			(effects
				(font
					(size 1.27 1.27)
					(thickness 0.15)
				)
				(justify left bottom)
				(hide yes)
			)
		)
		(property "Description" ""
			(at 290.83 231.14 0)
			(effects
				(font
					(size 1.27 1.27)
				)
			)
		)
		(property "Author" "Antmicro"
			(at 299.72 238.76 0)
			(effects
				(font
					(size 1.27 1.27)
					(thickness 0.15)
				)
				(justify left bottom)
				(hide yes)
			)
		)
		(property "License" "Apache-2.0"
			(at 299.72 241.3 0)
			(effects
				(font
					(size 1.27 1.27)
					(thickness 0.15)
				)
				(justify left bottom)
				(hide yes)
			)
		)
		(pin "1"
		)
		(instances
			(project "k410t-devboard"
				(path ""
					(reference "#PWR0415")
					(unit 1)
				)
			)
		)
	)
	(symbol
		(lib_id "antmicropower:GND")
		(at 245.11 154.94 0)
		(unit 1)
		(exclude_from_sim no)
		(in_bom yes)
		(on_board yes)
		(dnp no)
		(fields_autoplaced yes)
		(property "Reference" "#PWR0410"
			(at 245.11 161.29 0)
			(effects
				(font
					(size 1.27 1.27)
				)
				(hide yes)
			)
		)
		(property "Value" "GND"
			(at 245.11 158.75 0)
			(effects
				(font
					(size 1.27 1.27)
				)
			)
		)
		(property "Footprint" ""
			(at 254 162.56 0)
			(effects
				(font
					(size 1.27 1.27)
					(thickness 0.15)
				)
				(justify left bottom)
				(hide yes)
			)
		)
		(property "Datasheet" ""
			(at 254 167.64 0)
			(effects
				(font
					(size 1.27 1.27)
					(thickness 0.15)
				)
				(justify left bottom)
				(hide yes)
			)
		)
		(property "Description" ""
			(at 245.11 154.94 0)
			(effects
				(font
					(size 1.27 1.27)
				)
			)
		)
		(property "Author" "Antmicro"
			(at 254 162.56 0)
			(effects
				(font
					(size 1.27 1.27)
					(thickness 0.15)
				)
				(justify left bottom)
				(hide yes)
			)
		)
		(property "License" "Apache-2.0"
			(at 254 165.1 0)
			(effects
				(font
					(size 1.27 1.27)
					(thickness 0.15)
				)
				(justify left bottom)
				(hide yes)
			)
		)
		(pin "1"
		)
		(instances
			(project "k410t-devboard"
				(path ""
					(reference "#PWR0410")
					(unit 1)
				)
			)
		)
	)
	(symbol
		(lib_id "antmicropower:GND")
		(at 119.38 162.56 0)
		(unit 1)
		(exclude_from_sim no)
		(in_bom yes)
		(on_board yes)
		(dnp no)
		(property "Reference" "#PWR0378"
			(at 119.38 168.91 0)
			(effects
				(font
					(size 1.27 1.27)
				)
				(hide yes)
			)
		)
		(property "Value" "GND"
			(at 119.38 166.37 0)
			(effects
				(font
					(size 1.27 1.27)
				)
			)
		)
		(property "Footprint" ""
			(at 128.27 170.18 0)
			(effects
				(font
					(size 1.27 1.27)
					(thickness 0.15)
				)
				(justify left bottom)
				(hide yes)
			)
		)
		(property "Datasheet" ""
			(at 128.27 175.26 0)
			(effects
				(font
					(size 1.27 1.27)
					(thickness 0.15)
				)
				(justify left bottom)
				(hide yes)
			)
		)
		(property "Description" ""
			(at 119.38 162.56 0)
			(effects
				(font
					(size 1.27 1.27)
				)
			)
		)
		(property "Author" "Antmicro"
			(at 128.27 170.18 0)
			(effects
				(font
					(size 1.27 1.27)
					(thickness 0.15)
				)
				(justify left bottom)
				(hide yes)
			)
		)
		(property "License" "Apache-2.0"
			(at 128.27 172.72 0)
			(effects
				(font
					(size 1.27 1.27)
					(thickness 0.15)
				)
				(justify left bottom)
				(hide yes)
			)
		)
		(pin "1"
		)
		(instances
			(project "k410t-devboard"
				(path ""
					(reference "#PWR0378")
					(unit 1)
				)
			)
		)
	)
	(symbol
		(lib_id "k410t-devboard:Net-Tie_2")
		(at 391.16 161.29 0)
		(unit 1)
		(exclude_from_sim no)
		(in_bom yes)
		(on_board yes)
		(dnp no)
		(fields_autoplaced yes)
		(property "Reference" "NT1"
			(at 391.16 160.02 0)
			(effects
				(font
					(size 1.27 1.27)
				)
				(hide yes)
			)
		)
		(property "Value" "Net-Tie_2"
			(at 393.065 158.75 0)
			(effects
				(font
					(size 1.27 1.27)
					(thickness 0.15)
				)
				(hide yes)
			)
		)
		(property "Footprint" "antmicro-footprints:NetTie-2_SMD_Pad0.127mm"
			(at 412.75 166.37 0)
			(effects
				(font
					(size 1.27 1.27)
					(thickness 0.15)
				)
				(justify left bottom)
				(hide yes)
			)
		)
		(property "Datasheet" ""
			(at 412.75 168.91 0)
			(effects
				(font
					(size 1.27 1.27)
					(thickness 0.15)
				)
				(justify left bottom)
				(hide yes)
			)
		)
		(property "Description" ""
			(at 391.16 161.29 0)
			(effects
				(font
					(size 1.27 1.27)
				)
			)
		)
		(property "MPN" ""
			(at 412.75 170.18 0)
			(effects
				(font
					(size 1.27 1.27)
				)
				(justify left)
				(hide yes)
			)
		)
		(property "Manufacturer" ""
			(at 412.75 172.72 0)
			(effects
				(font
					(size 1.27 1.27)
				)
				(justify left)
				(hide yes)
			)
		)
		(property "Author" "Antmicro"
			(at 412.75 176.53 0)
			(effects
				(font
					(size 1.27 1.27)
					(thickness 0.15)
				)
				(justify left bottom)
				(hide yes)
			)
		)
		(property "License" "Apache-2.0"
			(at 412.75 179.07 0)
			(effects
				(font
					(size 1.27 1.27)
					(thickness 0.15)
				)
				(justify left bottom)
				(hide yes)
			)
		)
		(pin "1"
		)
		(pin "2"
		)
		(instances
			(project "k410t-devboard"
				(path ""
					(reference "NT1")
					(unit 1)
				)
			)
		)
	)
	(symbol
		(lib_id "antmicropower:GND")
		(at 213.36 59.69 0)
		(unit 1)
		(exclude_from_sim no)
		(in_bom yes)
		(on_board yes)
		(dnp no)
		(fields_autoplaced yes)
		(property "Reference" "#PWR0399"
			(at 213.36 66.04 0)
			(effects
				(font
					(size 1.27 1.27)
				)
				(hide yes)
			)
		)
		(property "Value" "GND"
			(at 213.36 63.5 0)
			(effects
				(font
					(size 1.27 1.27)
				)
			)
		)
		(property "Footprint" ""
			(at 222.25 67.31 0)
			(effects
				(font
					(size 1.27 1.27)
					(thickness 0.15)
				)
				(justify left bottom)
				(hide yes)
			)
		)
		(property "Datasheet" ""
			(at 222.25 72.39 0)
			(effects
				(font
					(size 1.27 1.27)
					(thickness 0.15)
				)
				(justify left bottom)
				(hide yes)
			)
		)
		(property "Description" ""
			(at 213.36 59.69 0)
			(effects
				(font
					(size 1.27 1.27)
				)
			)
		)
		(property "Author" "Antmicro"
			(at 222.25 67.31 0)
			(effects
				(font
					(size 1.27 1.27)
					(thickness 0.15)
				)
				(justify left bottom)
				(hide yes)
			)
		)
		(property "License" "Apache-2.0"
			(at 222.25 69.85 0)
			(effects
				(font
					(size 1.27 1.27)
					(thickness 0.15)
				)
				(justify left bottom)
				(hide yes)
			)
		)
		(pin "1"
		)
		(instances
			(project "k410t-devboard"
				(path ""
					(reference "#PWR0399")
					(unit 1)
				)
			)
		)
	)
	(symbol
		(lib_id "k410t-devboard:Net-Tie_2")
		(at 186.69 121.92 90)
		(unit 1)
		(exclude_from_sim no)
		(in_bom yes)
		(on_board yes)
		(dnp no)
		(fields_autoplaced yes)
		(property "Reference" "NT34"
			(at 185.42 121.92 0)
			(effects
				(font
					(size 1.27 1.27)
				)
				(hide yes)
			)
		)
		(property "Value" "Net-Tie_2"
			(at 185.42 120.0149 90)
			(effects
				(font
					(size 1.27 1.27)
					(thickness 0.15)
				)
				(justify left)
				(hide yes)
			)
		)
		(property "Footprint" "antmicro-footprints:NetTie-2_SMD_Pad0.127mm"
			(at 191.77 100.33 0)
			(effects
				(font
					(size 1.27 1.27)
					(thickness 0.15)
				)
				(justify left bottom)
				(hide yes)
			)
		)
		(property "Datasheet" ""
			(at 194.31 100.33 0)
			(effects
				(font
					(size 1.27 1.27)
					(thickness 0.15)
				)
				(justify left bottom)
				(hide yes)
			)
		)
		(property "Description" ""
			(at 186.69 121.92 0)
			(effects
				(font
					(size 1.27 1.27)
				)
			)
		)
		(property "MPN" ""
			(at 195.58 100.33 0)
			(effects
				(font
					(size 1.27 1.27)
				)
				(justify left)
				(hide yes)
			)
		)
		(property "Manufacturer" ""
			(at 198.12 100.33 0)
			(effects
				(font
					(size 1.27 1.27)
				)
				(justify left)
				(hide yes)
			)
		)
		(property "Author" "Antmicro"
			(at 201.93 100.33 0)
			(effects
				(font
					(size 1.27 1.27)
					(thickness 0.15)
				)
				(justify left bottom)
				(hide yes)
			)
		)
		(property "License" "Apache-2.0"
			(at 204.47 100.33 0)
			(effects
				(font
					(size 1.27 1.27)
					(thickness 0.15)
				)
				(justify left bottom)
				(hide yes)
			)
		)
		(pin "1"
		)
		(pin "2"
		)
		(instances
			(project "k410t-devboard"
				(path ""
					(reference "NT34")
					(unit 1)
				)
			)
		)
	)
	(symbol
		(lib_id "antmicroCapacitorsmisc:C_22u_25V_0805")
		(at 59.69 189.23 90)
		(unit 1)
		(exclude_from_sim no)
		(in_bom yes)
		(on_board yes)
		(dnp no)
		(property "Reference" "C320"
			(at 60.96 184.15 90)
			(effects
				(font
					(size 1.27 1.27)
				)
				(justify right)
			)
		)
		(property "Value" "C_22u_25V_0805"
			(at 63.5 189.23 0)
			(effects
				(font
					(size 1.27 1.27)
				)
				(hide yes)
			)
		)
		(property "Footprint" "antmicro-footprints:C_0805_2012Metric"
			(at 54.61 184.15 0)
			(effects
				(font
					(size 1.27 1.27)
				)
				(justify left)
				(hide yes)
			)
		)
		(property "Datasheet" "https://product.samsungsem.com/mlcc/CL21A226MAYNNN.do"
			(at 59.69 189.23 0)
			(effects
				(font
					(size 1.27 1.27)
				)
				(hide yes)
			)
		)
		(property "Description" ""
			(at 59.69 189.23 0)
			(effects
				(font
					(size 1.27 1.27)
				)
			)
		)
		(property "Manufacturer" "Samsung Electro-Mechanics"
			(at 49.53 184.15 0)
			(effects
				(font
					(size 1.27 1.27)
				)
				(justify left)
				(hide yes)
			)
		)
		(property "MPN" "CL21A226MAYNNNE"
			(at 52.07 184.15 0)
			(effects
				(font
					(size 1.27 1.27)
				)
				(justify left)
				(hide yes)
			)
		)
		(property "Val" "22u"
			(at 60.96 187.96 90)
			(effects
				(font
					(size 1.27 1.27)
				)
				(justify right)
			)
		)
		(property "License" "Apache-2.0"
			(at 82.55 168.91 0)
			(effects
				(font
					(size 1.27 1.27)
					(thickness 0.15)
				)
				(justify left bottom)
				(hide yes)
			)
		)
		(property "Author" "Antmicro"
			(at 85.09 168.91 0)
			(effects
				(font
					(size 1.27 1.27)
					(thickness 0.15)
				)
				(justify left bottom)
				(hide yes)
			)
		)
		(property "Voltage" "25V"
			(at 60.96 190.5 90)
			(effects
				(font
					(size 1.27 1.27)
				)
				(justify right)
			)
		)
		(property "Dielectric" "X5R"
			(at 90.17 168.91 0)
			(effects
				(font
					(size 1.27 1.27)
				)
				(justify left bottom)
				(hide yes)
			)
		)
		(pin "1"
		)
		(pin "2"
		)
		(instances
			(project "k410t-devboard"
				(path ""
					(reference "C320")
					(unit 1)
				)
			)
		)
	)
	(symbol
		(lib_id "antmicroResistors0402:R_0R_0402")
		(at 189.23 207.01 90)
		(unit 1)
		(exclude_from_sim no)
		(in_bom no)
		(on_board yes)
		(dnp yes)
		(property "Reference" "R301"
			(at 191.77 203.2 90)
			(effects
				(font
					(size 1.27 1.27)
				)
				(justify right)
			)
		)
		(property "Value" "R_0R_0402"
			(at 201.93 186.69 0)
			(effects
				(font
					(size 1.27 1.27)
					(thickness 0.15)
				)
				(justify left bottom)
				(hide yes)
			)
		)
		(property "Footprint" "antmicro-footprints:R_0402_1005Metric"
			(at 204.47 186.69 0)
			(effects
				(font
					(size 1.27 1.27)
					(thickness 0.15)
				)
				(justify left bottom)
				(hide yes)
			)
		)
		(property "Datasheet" "https://industrial.panasonic.com/cdbs/www-data/pdf/RDA0000/AOA0000C301.pdf"
			(at 207.01 186.69 0)
			(effects
				(font
					(size 1.27 1.27)
					(thickness 0.15)
				)
				(justify left bottom)
				(hide yes)
			)
		)
		(property "Description" ""
			(at 189.23 207.01 0)
			(effects
				(font
					(size 1.27 1.27)
				)
			)
		)
		(property "Manufacturer" "Panasonic"
			(at 212.09 186.69 0)
			(effects
				(font
					(size 1.27 1.27)
					(thickness 0.15)
				)
				(justify left bottom)
				(hide yes)
			)
		)
		(property "MPN" "ERJ2GE0R00X"
			(at 209.55 186.69 0)
			(effects
				(font
					(size 1.27 1.27)
					(thickness 0.15)
				)
				(justify left bottom)
				(hide yes)
			)
		)
		(property "Val" "0R"
			(at 191.77 205.74 90)
			(effects
				(font
					(size 1.27 1.27)
					(thickness 0.15)
				)
				(justify right)
			)
		)
		(property "DNP" "DNP"
			(at 189.23 202.565 0)
			(effects
				(font
					(size 1.27 1.27)
				)
				(justify right)
			)
		)
		(property "License" "Apache-2.0"
			(at 214.63 186.69 0)
			(effects
				(font
					(size 1.27 1.27)
					(thickness 0.15)
				)
				(justify left bottom)
				(hide yes)
			)
		)
		(property "Author" "Antmicro"
			(at 217.17 186.69 0)
			(effects
				(font
					(size 1.27 1.27)
					(thickness 0.15)
				)
				(justify left bottom)
				(hide yes)
			)
		)
		(property "Tolerance" "~"
			(at 199.39 186.69 0)
			(effects
				(font
					(size 1.27 1.27)
				)
				(justify left bottom)
				(hide yes)
			)
		)
		(property "Current" "1A"
			(at 191.77 208.2799 90)
			(effects
				(font
					(size 1.27 1.27)
					(thickness 0.15)
				)
				(justify right)
				(hide yes)
			)
		)
		(pin "1"
		)
		(pin "2"
		)
		(instances
			(project "k410t-devboard"
				(path ""
					(reference "R301")
					(unit 1)
				)
			)
		)
	)
	(symbol
		(lib_id "antmicroCapacitors0402:C_10u_0402")
		(at 355.6 223.52 90)
		(unit 1)
		(exclude_from_sim no)
		(in_bom yes)
		(on_board yes)
		(dnp no)
		(property "Reference" "C355"
			(at 356.235 219.075 90)
			(effects
				(font
					(size 1.27 1.27)
				)
				(justify right)
			)
		)
		(property "Value" "C_10u_0402"
			(at 365.76 203.2 0)
			(effects
				(font
					(size 1.27 1.27)
					(thickness 0.15)
				)
				(justify left bottom)
				(hide yes)
			)
		)
		(property "Footprint" "antmicro-footprints:C_0402_1005Metric"
			(at 368.3 203.2 0)
			(effects
				(font
					(size 1.27 1.27)
					(thickness 0.15)
				)
				(justify left bottom)
				(hide yes)
			)
		)
		(property "Datasheet" "https://www.yageo.com/en/Chart/Download/pdf/CC0402MRX5R5BB106"
			(at 370.84 203.2 0)
			(effects
				(font
					(size 1.27 1.27)
					(thickness 0.15)
				)
				(justify left bottom)
				(hide yes)
			)
		)
		(property "Description" ""
			(at 355.6 223.52 0)
			(effects
				(font
					(size 1.27 1.27)
				)
			)
		)
		(property "Manufacturer" "YAGEO"
			(at 375.92 203.2 0)
			(effects
				(font
					(size 1.27 1.27)
					(thickness 0.15)
				)
				(justify left bottom)
				(hide yes)
			)
		)
		(property "MPN" "CC0402MRX5R5BB106"
			(at 373.38 203.2 0)
			(effects
				(font
					(size 1.27 1.27)
					(thickness 0.15)
				)
				(justify left bottom)
				(hide yes)
			)
		)
		(property "Val" "10u"
			(at 356.235 222.885 90)
			(effects
				(font
					(size 1.27 1.27)
					(thickness 0.15)
				)
				(justify right)
			)
		)
		(property "License" "Apache-2.0"
			(at 378.46 203.2 0)
			(effects
				(font
					(size 1.27 1.27)
					(thickness 0.15)
				)
				(justify left bottom)
				(hide yes)
			)
		)
		(property "Author" "Antmicro"
			(at 381 203.2 0)
			(effects
				(font
					(size 1.27 1.27)
					(thickness 0.15)
				)
				(justify left bottom)
				(hide yes)
			)
		)
		(property "Voltage" ""
			(at 383.54 203.2 0)
			(effects
				(font
					(size 1.27 1.27)
				)
				(justify left bottom)
				(hide yes)
			)
		)
		(property "Dielectric" ""
			(at 386.08 203.2 0)
			(effects
				(font
					(size 1.27 1.27)
				)
				(justify left bottom)
				(hide yes)
			)
		)
		(pin "1"
		)
		(pin "2"
		)
		(instances
			(project "k410t-devboard"
				(path ""
					(reference "C355")
					(unit 1)
				)
			)
		)
	)
	(symbol
		(lib_id "antmicropower:+3.3V")
		(at 281.94 160.02 0)
		(unit 1)
		(exclude_from_sim no)
		(in_bom yes)
		(on_board yes)
		(dnp no)
		(fields_autoplaced yes)
		(property "Reference" "#PWR0383"
			(at 281.94 163.83 0)
			(effects
				(font
					(size 1.27 1.27)
				)
				(hide yes)
			)
		)
		(property "Value" "+3V3"
			(at 281.94 156.464 0)
			(effects
				(font
					(size 1.27 1.27)
				)
			)
		)
		(property "Footprint" ""
			(at 281.94 160.02 0)
			(effects
				(font
					(size 1.27 1.27)
				)
				(hide yes)
			)
		)
		(property "Datasheet" ""
			(at 281.94 160.02 0)
			(effects
				(font
					(size 1.27 1.27)
				)
				(hide yes)
			)
		)
		(property "Description" ""
			(at 281.94 160.02 0)
			(effects
				(font
					(size 1.27 1.27)
				)
			)
		)
		(pin "1"
		)
		(instances
			(project "k410t-devboard"
				(path ""
					(reference "#PWR0383")
					(unit 1)
				)
			)
		)
	)
	(symbol
		(lib_id "antmicroResistors0402:R_47k_0402")
		(at 265.43 44.45 90)
		(unit 1)
		(exclude_from_sim no)
		(in_bom yes)
		(on_board yes)
		(dnp no)
		(property "Reference" "R322"
			(at 266.7 40.64 90)
			(effects
				(font
					(size 1.27 1.27)
				)
				(justify right)
			)
		)
		(property "Value" "R_47k_0402"
			(at 278.13 24.13 0)
			(effects
				(font
					(size 1.27 1.27)
					(thickness 0.15)
				)
				(justify left bottom)
				(hide yes)
			)
		)
		(property "Footprint" "antmicro-footprints:R_0402_1005Metric"
			(at 280.67 24.13 0)
			(effects
				(font
					(size 1.27 1.27)
					(thickness 0.15)
				)
				(justify left bottom)
				(hide yes)
			)
		)
		(property "Datasheet" "https://www.bourns.com/docs/product-datasheets/cr.pdf"
			(at 283.21 24.13 0)
			(effects
				(font
					(size 1.27 1.27)
					(thickness 0.15)
				)
				(justify left bottom)
				(hide yes)
			)
		)
		(property "Description" ""
			(at 265.43 44.45 0)
			(effects
				(font
					(size 1.27 1.27)
				)
			)
		)
		(property "Manufacturer" "Bourns"
			(at 288.29 24.13 0)
			(effects
				(font
					(size 1.27 1.27)
					(thickness 0.15)
				)
				(justify left bottom)
				(hide yes)
			)
		)
		(property "MPN" "CR0402-FX-4702GLF"
			(at 285.75 24.13 0)
			(effects
				(font
					(size 1.27 1.27)
					(thickness 0.15)
				)
				(justify left bottom)
				(hide yes)
			)
		)
		(property "Val" "47k"
			(at 266.7 43.18 90)
			(effects
				(font
					(size 1.27 1.27)
					(thickness 0.15)
				)
				(justify right)
			)
		)
		(property "License" "Apache-2.0"
			(at 290.83 24.13 0)
			(effects
				(font
					(size 1.27 1.27)
					(thickness 0.15)
				)
				(justify left bottom)
				(hide yes)
			)
		)
		(property "Author" "Antmicro"
			(at 293.37 24.13 0)
			(effects
				(font
					(size 1.27 1.27)
					(thickness 0.15)
				)
				(justify left bottom)
				(hide yes)
			)
		)
		(property "Tolerance" "1%"
			(at 275.59 24.13 0)
			(effects
				(font
					(size 1.27 1.27)
				)
				(justify left bottom)
				(hide yes)
			)
		)
		(pin "1"
		)
		(pin "2"
		)
		(instances
			(project "k410t-devboard"
				(path ""
					(reference "R322")
					(unit 1)
				)
			)
		)
	)
	(symbol
		(lib_id "k410t-devboard:Net-Tie_2")
		(at 190.5 260.35 90)
		(unit 1)
		(exclude_from_sim no)
		(in_bom yes)
		(on_board yes)
		(dnp no)
		(fields_autoplaced yes)
		(property "Reference" "NT30"
			(at 189.23 260.35 0)
			(effects
				(font
					(size 1.27 1.27)
				)
				(hide yes)
			)
		)
		(property "Value" "Net-Tie_2"
			(at 189.23 258.4449 90)
			(effects
				(font
					(size 1.27 1.27)
					(thickness 0.15)
				)
				(justify left)
				(hide yes)
			)
		)
		(property "Footprint" "antmicro-footprints:NetTie-2_SMD_Pad0.127mm"
			(at 195.58 238.76 0)
			(effects
				(font
					(size 1.27 1.27)
					(thickness 0.15)
				)
				(justify left bottom)
				(hide yes)
			)
		)
		(property "Datasheet" ""
			(at 198.12 238.76 0)
			(effects
				(font
					(size 1.27 1.27)
					(thickness 0.15)
				)
				(justify left bottom)
				(hide yes)
			)
		)
		(property "Description" ""
			(at 190.5 260.35 0)
			(effects
				(font
					(size 1.27 1.27)
				)
			)
		)
		(property "MPN" ""
			(at 199.39 238.76 0)
			(effects
				(font
					(size 1.27 1.27)
				)
				(justify left)
				(hide yes)
			)
		)
		(property "Manufacturer" ""
			(at 201.93 238.76 0)
			(effects
				(font
					(size 1.27 1.27)
				)
				(justify left)
				(hide yes)
			)
		)
		(property "Author" "Antmicro"
			(at 205.74 238.76 0)
			(effects
				(font
					(size 1.27 1.27)
					(thickness 0.15)
				)
				(justify left bottom)
				(hide yes)
			)
		)
		(property "License" "Apache-2.0"
			(at 208.28 238.76 0)
			(effects
				(font
					(size 1.27 1.27)
					(thickness 0.15)
				)
				(justify left bottom)
				(hide yes)
			)
		)
		(pin "1"
		)
		(pin "2"
		)
		(instances
			(project "k410t-devboard"
				(path ""
					(reference "NT30")
					(unit 1)
				)
			)
		)
	)
	(symbol
		(lib_id "antmicropower:GND")
		(at 119.38 215.9 0)
		(unit 1)
		(exclude_from_sim no)
		(in_bom yes)
		(on_board yes)
		(dnp no)
		(fields_autoplaced yes)
		(property "Reference" "#PWR0386"
			(at 119.38 222.25 0)
			(effects
				(font
					(size 1.27 1.27)
				)
				(hide yes)
			)
		)
		(property "Value" "GND"
			(at 119.38 219.71 0)
			(effects
				(font
					(size 1.27 1.27)
				)
			)
		)
		(property "Footprint" ""
			(at 128.27 223.52 0)
			(effects
				(font
					(size 1.27 1.27)
					(thickness 0.15)
				)
				(justify left bottom)
				(hide yes)
			)
		)
		(property "Datasheet" ""
			(at 128.27 228.6 0)
			(effects
				(font
					(size 1.27 1.27)
					(thickness 0.15)
				)
				(justify left bottom)
				(hide yes)
			)
		)
		(property "Description" ""
			(at 119.38 215.9 0)
			(effects
				(font
					(size 1.27 1.27)
				)
			)
		)
		(property "Author" "Antmicro"
			(at 128.27 223.52 0)
			(effects
				(font
					(size 1.27 1.27)
					(thickness 0.15)
				)
				(justify left bottom)
				(hide yes)
			)
		)
		(property "License" "Apache-2.0"
			(at 128.27 226.06 0)
			(effects
				(font
					(size 1.27 1.27)
					(thickness 0.15)
				)
				(justify left bottom)
				(hide yes)
			)
		)
		(pin "1"
		)
		(instances
			(project "k410t-devboard"
				(path ""
					(reference "#PWR0386")
					(unit 1)
				)
			)
		)
	)
	(symbol
		(lib_id "antmicropower:GND")
		(at 393.7 217.17 0)
		(mirror y)
		(unit 1)
		(exclude_from_sim no)
		(in_bom yes)
		(on_board yes)
		(dnp no)
		(property "Reference" "#PWR0455"
			(at 393.7 223.52 0)
			(effects
				(font
					(size 1.27 1.27)
				)
				(hide yes)
			)
		)
		(property "Value" "GND"
			(at 393.7 220.98 0)
			(effects
				(font
					(size 1.27 1.27)
				)
			)
		)
		(property "Footprint" ""
			(at 384.81 224.79 0)
			(effects
				(font
					(size 1.27 1.27)
					(thickness 0.15)
				)
				(justify left bottom)
				(hide yes)
			)
		)
		(property "Datasheet" ""
			(at 384.81 229.87 0)
			(effects
				(font
					(size 1.27 1.27)
					(thickness 0.15)
				)
				(justify left bottom)
				(hide yes)
			)
		)
		(property "Description" ""
			(at 393.7 217.17 0)
			(effects
				(font
					(size 1.27 1.27)
				)
			)
		)
		(property "Author" "Antmicro"
			(at 384.81 224.79 0)
			(effects
				(font
					(size 1.27 1.27)
					(thickness 0.15)
				)
				(justify left bottom)
				(hide yes)
			)
		)
		(property "License" "Apache-2.0"
			(at 384.81 227.33 0)
			(effects
				(font
					(size 1.27 1.27)
					(thickness 0.15)
				)
				(justify left bottom)
				(hide yes)
			)
		)
		(pin "1"
		)
		(instances
			(project "k410t-devboard"
				(path ""
					(reference "#PWR0455")
					(unit 1)
				)
			)
		)
	)
	(symbol
		(lib_id "antmicroResistors0402:R_205k_0402")
		(at 388.62 73.66 90)
		(unit 1)
		(exclude_from_sim no)
		(in_bom yes)
		(on_board yes)
		(dnp no)
		(fields_autoplaced yes)
		(property "Reference" "R332"
			(at 390.525 69.8499 90)
			(effects
				(font
					(size 1.27 1.27)
				)
				(justify right)
			)
		)
		(property "Value" "R_205k_0402"
			(at 401.32 53.34 0)
			(effects
				(font
					(size 1.27 1.27)
					(thickness 0.15)
				)
				(justify left bottom)
				(hide yes)
			)
		)
		(property "Footprint" "antmicro-footprints:R_0402_1005Metric"
			(at 403.86 53.34 0)
			(effects
				(font
					(size 1.27 1.27)
					(thickness 0.15)
				)
				(justify left bottom)
				(hide yes)
			)
		)
		(property "Datasheet" "https://www.bourns.com/docs/product-datasheets/cr.pdf"
			(at 406.4 53.34 0)
			(effects
				(font
					(size 1.27 1.27)
					(thickness 0.15)
				)
				(justify left bottom)
				(hide yes)
			)
		)
		(property "Description" ""
			(at 388.62 73.66 0)
			(effects
				(font
					(size 1.27 1.27)
				)
			)
		)
		(property "Manufacturer" "Bourns"
			(at 411.48 53.34 0)
			(effects
				(font
					(size 1.27 1.27)
					(thickness 0.15)
				)
				(justify left bottom)
				(hide yes)
			)
		)
		(property "MPN" "CR0402-FX-2053GLF"
			(at 408.94 53.34 0)
			(effects
				(font
					(size 1.27 1.27)
					(thickness 0.15)
				)
				(justify left bottom)
				(hide yes)
			)
		)
		(property "Val" "205k"
			(at 390.525 72.3899 90)
			(effects
				(font
					(size 1.27 1.27)
					(thickness 0.15)
				)
				(justify right)
			)
		)
		(property "License" "Apache-2.0"
			(at 414.02 53.34 0)
			(effects
				(font
					(size 1.27 1.27)
					(thickness 0.15)
				)
				(justify left bottom)
				(hide yes)
			)
		)
		(property "Author" "Antmicro"
			(at 416.56 53.34 0)
			(effects
				(font
					(size 1.27 1.27)
					(thickness 0.15)
				)
				(justify left bottom)
				(hide yes)
			)
		)
		(property "Tolerance" "1%"
			(at 398.78 53.34 0)
			(effects
				(font
					(size 1.27 1.27)
				)
				(justify left bottom)
				(hide yes)
			)
		)
		(pin "1"
		)
		(pin "2"
		)
		(instances
			(project "k410t-devboard"
				(path ""
					(reference "R332")
					(unit 1)
				)
			)
		)
	)
	(symbol
		(lib_id "antmicropower:GND")
		(at 49.53 212.09 0)
		(unit 1)
		(exclude_from_sim no)
		(in_bom yes)
		(on_board yes)
		(dnp no)
		(fields_autoplaced yes)
		(property "Reference" "#PWR0364"
			(at 49.53 218.44 0)
			(effects
				(font
					(size 1.27 1.27)
				)
				(hide yes)
			)
		)
		(property "Value" "GND"
			(at 49.53 215.9 0)
			(effects
				(font
					(size 1.27 1.27)
				)
			)
		)
		(property "Footprint" ""
			(at 58.42 219.71 0)
			(effects
				(font
					(size 1.27 1.27)
					(thickness 0.15)
				)
				(justify left bottom)
				(hide yes)
			)
		)
		(property "Datasheet" ""
			(at 58.42 224.79 0)
			(effects
				(font
					(size 1.27 1.27)
					(thickness 0.15)
				)
				(justify left bottom)
				(hide yes)
			)
		)
		(property "Description" ""
			(at 49.53 212.09 0)
			(effects
				(font
					(size 1.27 1.27)
				)
			)
		)
		(property "Author" "Antmicro"
			(at 58.42 219.71 0)
			(effects
				(font
					(size 1.27 1.27)
					(thickness 0.15)
				)
				(justify left bottom)
				(hide yes)
			)
		)
		(property "License" "Apache-2.0"
			(at 58.42 222.25 0)
			(effects
				(font
					(size 1.27 1.27)
					(thickness 0.15)
				)
				(justify left bottom)
				(hide yes)
			)
		)
		(pin "1"
		)
		(instances
			(project "k410t-devboard"
				(path ""
					(reference "#PWR0364")
					(unit 1)
				)
			)
		)
	)
	(symbol
		(lib_id "antmicroCapacitors0402:C_1u_0402")
		(at 341.63 168.91 90)
		(unit 1)
		(exclude_from_sim no)
		(in_bom yes)
		(on_board yes)
		(dnp no)
		(fields_autoplaced yes)
		(property "Reference" "C352"
			(at 344.17 165.0935 90)
			(effects
				(font
					(size 1.27 1.27)
				)
				(justify right)
			)
		)
		(property "Value" "C_1u_0402"
			(at 351.79 148.59 0)
			(effects
				(font
					(size 1.27 1.27)
					(thickness 0.15)
				)
				(justify left bottom)
				(hide yes)
			)
		)
		(property "Footprint" "antmicro-footprints:C_0402_1005Metric"
			(at 354.33 148.59 0)
			(effects
				(font
					(size 1.27 1.27)
					(thickness 0.15)
				)
				(justify left bottom)
				(hide yes)
			)
		)
		(property "Datasheet" "https://product.tdk.com/en/search/capacitor/ceramic/mlcc/info?part_no=C1005X6S1A105K050BC"
			(at 356.87 148.59 0)
			(effects
				(font
					(size 1.27 1.27)
					(thickness 0.15)
				)
				(justify left bottom)
				(hide yes)
			)
		)
		(property "Description" ""
			(at 341.63 168.91 0)
			(effects
				(font
					(size 1.27 1.27)
				)
			)
		)
		(property "Manufacturer" "TDK"
			(at 361.95 148.59 0)
			(effects
				(font
					(size 1.27 1.27)
					(thickness 0.15)
				)
				(justify left bottom)
				(hide yes)
			)
		)
		(property "MPN" "C1005X6S1A105K050BC"
			(at 359.41 148.59 0)
			(effects
				(font
					(size 1.27 1.27)
					(thickness 0.15)
				)
				(justify left bottom)
				(hide yes)
			)
		)
		(property "Val" "1u"
			(at 344.17 167.6335 90)
			(effects
				(font
					(size 1.27 1.27)
					(thickness 0.15)
				)
				(justify right)
			)
		)
		(property "License" "Apache-2.0"
			(at 364.49 148.59 0)
			(effects
				(font
					(size 1.27 1.27)
					(thickness 0.15)
				)
				(justify left bottom)
				(hide yes)
			)
		)
		(property "Author" "Antmicro"
			(at 367.03 148.59 0)
			(effects
				(font
					(size 1.27 1.27)
					(thickness 0.15)
				)
				(justify left bottom)
				(hide yes)
			)
		)
		(property "Voltage" ""
			(at 369.57 148.59 0)
			(effects
				(font
					(size 1.27 1.27)
				)
				(justify left bottom)
				(hide yes)
			)
		)
		(property "Dielectric" ""
			(at 372.11 148.59 0)
			(effects
				(font
					(size 1.27 1.27)
				)
				(justify left bottom)
				(hide yes)
			)
		)
		(pin "1"
		)
		(pin "2"
		)
		(instances
			(project "k410t-devboard"
				(path ""
					(reference "C352")
					(unit 1)
				)
			)
		)
	)
	(symbol
		(lib_id "antmicroResistors0402:R_100k_0402")
		(at 25.4 228.6 90)
		(unit 1)
		(exclude_from_sim no)
		(in_bom no)
		(on_board yes)
		(dnp yes)
		(property "Reference" "R277"
			(at 26.67 224.79 90)
			(effects
				(font
					(size 1.27 1.27)
				)
				(justify right)
			)
		)
		(property "Value" "R_100k_0402"
			(at 29.21 228.6 0)
			(effects
				(font
					(size 1.27 1.27)
				)
				(hide yes)
			)
		)
		(property "Footprint" "antmicro-footprints:R_0402_1005Metric"
			(at 20.32 223.52 0)
			(effects
				(font
					(size 1.27 1.27)
				)
				(justify left)
				(hide yes)
			)
		)
		(property "Datasheet" "https://www.bourns.com/docs/product-datasheets/cr.pdf"
			(at 25.4 228.6 0)
			(effects
				(font
					(size 1.27 1.27)
				)
				(hide yes)
			)
		)
		(property "Description" ""
			(at 25.4 228.6 0)
			(effects
				(font
					(size 1.27 1.27)
				)
			)
		)
		(property "Manufacturer" "Bourns"
			(at 15.24 223.52 0)
			(effects
				(font
					(size 1.27 1.27)
				)
				(justify left)
				(hide yes)
			)
		)
		(property "MPN" "CR0402-FX-1003GLF"
			(at 17.78 223.52 0)
			(effects
				(font
					(size 1.27 1.27)
				)
				(justify left)
				(hide yes)
			)
		)
		(property "Val" "100k"
			(at 26.67 227.33 90)
			(effects
				(font
					(size 1.27 1.27)
				)
				(justify right)
			)
		)
		(property "DNP" "DNP"
			(at 25.4 224.155 0)
			(effects
				(font
					(size 1.27 1.27)
				)
				(justify right)
			)
		)
		(property "License" "Apache-2.0"
			(at 50.8 208.28 0)
			(effects
				(font
					(size 1.27 1.27)
					(thickness 0.15)
				)
				(justify left bottom)
				(hide yes)
			)
		)
		(property "Author" "Antmicro"
			(at 53.34 208.28 0)
			(effects
				(font
					(size 1.27 1.27)
					(thickness 0.15)
				)
				(justify left bottom)
				(hide yes)
			)
		)
		(property "Tolerance" "1%"
			(at 35.56 208.28 0)
			(effects
				(font
					(size 1.27 1.27)
				)
				(justify left bottom)
				(hide yes)
			)
		)
		(pin "1"
		)
		(pin "2"
		)
		(instances
			(project "k410t-devboard"
				(path ""
					(reference "R277")
					(unit 1)
				)
			)
		)
	)
	(symbol
		(lib_id "antmicroResistors0402:R_0R_0402")
		(at 256.54 198.12 90)
		(unit 1)
		(exclude_from_sim no)
		(in_bom no)
		(on_board yes)
		(dnp yes)
		(property "Reference" "R319"
			(at 258.445 194.31 90)
			(effects
				(font
					(size 1.27 1.27)
				)
				(justify right)
			)
		)
		(property "Value" "R_0R_0402"
			(at 269.24 177.8 0)
			(effects
				(font
					(size 1.27 1.27)
					(thickness 0.15)
				)
				(justify left bottom)
				(hide yes)
			)
		)
		(property "Footprint" "antmicro-footprints:R_0402_1005Metric"
			(at 271.78 177.8 0)
			(effects
				(font
					(size 1.27 1.27)
					(thickness 0.15)
				)
				(justify left bottom)
				(hide yes)
			)
		)
		(property "Datasheet" "https://industrial.panasonic.com/cdbs/www-data/pdf/RDA0000/AOA0000C301.pdf"
			(at 274.32 177.8 0)
			(effects
				(font
					(size 1.27 1.27)
					(thickness 0.15)
				)
				(justify left bottom)
				(hide yes)
			)
		)
		(property "Description" ""
			(at 256.54 198.12 0)
			(effects
				(font
					(size 1.27 1.27)
				)
			)
		)
		(property "Manufacturer" "Panasonic"
			(at 279.4 177.8 0)
			(effects
				(font
					(size 1.27 1.27)
					(thickness 0.15)
				)
				(justify left bottom)
				(hide yes)
			)
		)
		(property "MPN" "ERJ2GE0R00X"
			(at 276.86 177.8 0)
			(effects
				(font
					(size 1.27 1.27)
					(thickness 0.15)
				)
				(justify left bottom)
				(hide yes)
			)
		)
		(property "Val" "0R"
			(at 258.445 196.85 90)
			(effects
				(font
					(size 1.27 1.27)
					(thickness 0.15)
				)
				(justify right)
			)
		)
		(property "DNP" "DNP"
			(at 256.54 193.675 0)
			(effects
				(font
					(size 1.27 1.27)
				)
				(justify right)
			)
		)
		(property "License" "Apache-2.0"
			(at 281.94 177.8 0)
			(effects
				(font
					(size 1.27 1.27)
					(thickness 0.15)
				)
				(justify left bottom)
				(hide yes)
			)
		)
		(property "Author" "Antmicro"
			(at 284.48 177.8 0)
			(effects
				(font
					(size 1.27 1.27)
					(thickness 0.15)
				)
				(justify left bottom)
				(hide yes)
			)
		)
		(property "Tolerance" "~"
			(at 266.7 177.8 0)
			(effects
				(font
					(size 1.27 1.27)
				)
				(justify left bottom)
				(hide yes)
			)
		)
		(property "Current" "1A"
			(at 258.445 199.3899 90)
			(effects
				(font
					(size 1.27 1.27)
					(thickness 0.15)
				)
				(justify right)
				(hide yes)
			)
		)
		(pin "1"
		)
		(pin "2"
		)
		(instances
			(project "k410t-devboard"
				(path ""
					(reference "R319")
					(unit 1)
				)
			)
		)
	)
	(symbol
		(lib_id "antmicroFerriteBeadsandChips:FB_120Z_1.3A_Murata-BLM15PD_0402")
		(at 294.64 161.29 0)
		(unit 1)
		(exclude_from_sim no)
		(in_bom yes)
		(on_board yes)
		(dnp no)
		(fields_autoplaced yes)
		(property "Reference" "FB11"
			(at 297.1419 154.94 0)
			(effects
				(font
					(size 1.27 1.27)
				)
			)
		)
		(property "Value" "FB_120Z_1.3A_Murata-BLM15PD_0402"
			(at 297.1419 157.48 0)
			(effects
				(font
					(size 1.27 1.27)
					(thickness 0.15)
				)
				(hide yes)
			)
		)
		(property "Footprint" "antmicro-footprints:FB_0402_1005Metric"
			(at 308.61 166.37 0)
			(effects
				(font
					(size 1.27 1.27)
					(thickness 0.15)
				)
				(justify left bottom)
				(hide yes)
			)
		)
		(property "Datasheet" "https://www.murata.com/en-us/products/productdata/8796740059166/ENFA0018.pdf"
			(at 308.61 168.91 0)
			(effects
				(font
					(size 1.27 1.27)
					(thickness 0.15)
				)
				(justify left bottom)
				(hide yes)
			)
		)
		(property "Description" ""
			(at 294.64 161.29 0)
			(effects
				(font
					(size 1.27 1.27)
				)
			)
		)
		(property "MPN" "BLM15PD121SN1D"
			(at 308.61 171.45 0)
			(effects
				(font
					(size 1.27 1.27)
					(thickness 0.15)
				)
				(justify left bottom)
				(hide yes)
			)
		)
		(property "Manufacturer" "Murata"
			(at 308.61 173.99 0)
			(effects
				(font
					(size 1.27 1.27)
					(thickness 0.15)
				)
				(justify left bottom)
				(hide yes)
			)
		)
		(property "Author" "Antmicro"
			(at 308.61 176.53 0)
			(effects
				(font
					(size 1.27 1.27)
					(thickness 0.15)
				)
				(justify left bottom)
				(hide yes)
			)
		)
		(property "License" "Apache-2.0"
			(at 308.61 179.07 0)
			(effects
				(font
					(size 1.27 1.27)
					(thickness 0.15)
				)
				(justify left bottom)
				(hide yes)
			)
		)
		(property "Val" "120Z/1.3A"
			(at 297.1419 157.48 0)
			(effects
				(font
					(size 1.27 1.27)
				)
			)
		)
		(property "Current" ""
			(at 314.96 184.15 0)
			(effects
				(font
					(size 1.27 1.27)
					(thickness 0.15)
				)
				(justify left bottom)
				(hide yes)
			)
		)
		(pin "1"
		)
		(pin "2"
		)
		(instances
			(project "k410t-devboard"
				(path ""
					(reference "FB11")
					(unit 1)
				)
			)
		)
	)
	(symbol
		(lib_id "antmicropower:GND")
		(at 146.05 270.51 0)
		(unit 1)
		(exclude_from_sim no)
		(in_bom yes)
		(on_board yes)
		(dnp no)
		(fields_autoplaced yes)
		(property "Reference" "#PWR0391"
			(at 146.05 276.86 0)
			(effects
				(font
					(size 1.27 1.27)
				)
				(hide yes)
			)
		)
		(property "Value" "GND"
			(at 146.05 274.32 0)
			(effects
				(font
					(size 1.27 1.27)
				)
			)
		)
		(property "Footprint" ""
			(at 154.94 278.13 0)
			(effects
				(font
					(size 1.27 1.27)
					(thickness 0.15)
				)
				(justify left bottom)
				(hide yes)
			)
		)
		(property "Datasheet" ""
			(at 154.94 283.21 0)
			(effects
				(font
					(size 1.27 1.27)
					(thickness 0.15)
				)
				(justify left bottom)
				(hide yes)
			)
		)
		(property "Description" ""
			(at 146.05 270.51 0)
			(effects
				(font
					(size 1.27 1.27)
				)
			)
		)
		(property "Author" "Antmicro"
			(at 154.94 278.13 0)
			(effects
				(font
					(size 1.27 1.27)
					(thickness 0.15)
				)
				(justify left bottom)
				(hide yes)
			)
		)
		(property "License" "Apache-2.0"
			(at 154.94 280.67 0)
			(effects
				(font
					(size 1.27 1.27)
					(thickness 0.15)
				)
				(justify left bottom)
				(hide yes)
			)
		)
		(pin "1"
		)
		(instances
			(project "k410t-devboard"
				(path ""
					(reference "#PWR0391")
					(unit 1)
				)
			)
		)
	)
	(symbol
		(lib_id "antmicroTestPoints:TP_0.75mm_SMD")
		(at 71.12 129.54 90)
		(unit 1)
		(exclude_from_sim no)
		(in_bom yes)
		(on_board yes)
		(dnp no)
		(property "Reference" "TP5"
			(at 73.025 124.46 90)
			(effects
				(font
					(size 1.27 1.27)
				)
				(justify left)
			)
		)
		(property "Value" "TP_0.75mm_SMD"
			(at 73.66 129.54 0)
			(effects
				(font
					(size 1.27 1.27)
				)
				(hide yes)
			)
		)
		(property "Footprint" "antmicro-footprints:TP_SMD_0.75mm"
			(at 66.04 124.46 0)
			(effects
				(font
					(size 1.27 1.27)
				)
				(justify left)
				(hide yes)
			)
		)
		(property "Datasheet" ""
			(at 63.5 124.46 0)
			(effects
				(font
					(size 1.27 1.27)
				)
				(justify left)
				(hide yes)
			)
		)
		(property "Description" ""
			(at 71.12 129.54 0)
			(effects
				(font
					(size 1.27 1.27)
				)
			)
		)
		(property "MPN" ""
			(at 71.12 129.54 0)
			(effects
				(font
					(size 1.27 1.27)
				)
				(hide yes)
			)
		)
		(property "Manufacturer" ""
			(at 71.12 129.54 0)
			(effects
				(font
					(size 1.27 1.27)
				)
				(hide yes)
			)
		)
		(property "Author" "Antmicro"
			(at 86.36 114.3 0)
			(effects
				(font
					(size 1.27 1.27)
					(thickness 0.15)
				)
				(justify left bottom)
				(hide yes)
			)
		)
		(property "License" "Apache-2.0"
			(at 88.9 114.3 0)
			(effects
				(font
					(size 1.27 1.27)
					(thickness 0.15)
				)
				(justify left bottom)
				(hide yes)
			)
		)
		(pin "1"
		)
		(instances
			(project "k410t-devboard"
				(path ""
					(reference "TP5")
					(unit 1)
				)
			)
		)
	)
	(symbol
		(lib_id "antmicroCapacitors0402:C_1u_0402")
		(at 309.88 119.38 90)
		(unit 1)
		(exclude_from_sim no)
		(in_bom yes)
		(on_board yes)
		(dnp no)
		(property "Reference" "C348"
			(at 310.515 114.935 90)
			(effects
				(font
					(size 1.27 1.27)
				)
				(justify right)
			)
		)
		(property "Value" "C_1u_0402"
			(at 313.69 119.38 0)
			(effects
				(font
					(size 1.27 1.27)
				)
				(hide yes)
			)
		)
		(property "Footprint" "antmicro-footprints:C_0402_1005Metric"
			(at 322.58 99.06 0)
			(effects
				(font
					(size 1.27 1.27)
					(thickness 0.15)
				)
				(justify left bottom)
				(hide yes)
			)
		)
		(property "Datasheet" "https://product.tdk.com/en/search/capacitor/ceramic/mlcc/info?part_no=C1005X6S1A105K050BC"
			(at 325.12 99.06 0)
			(effects
				(font
					(size 1.27 1.27)
					(thickness 0.15)
				)
				(justify left bottom)
				(hide yes)
			)
		)
		(property "Description" ""
			(at 309.88 119.38 0)
			(effects
				(font
					(size 1.27 1.27)
				)
			)
		)
		(property "Manufacturer" "TDK"
			(at 330.2 99.06 0)
			(effects
				(font
					(size 1.27 1.27)
					(thickness 0.15)
				)
				(justify left bottom)
				(hide yes)
			)
		)
		(property "MPN" "C1005X6S1A105K050BC"
			(at 327.66 99.06 0)
			(effects
				(font
					(size 1.27 1.27)
					(thickness 0.15)
				)
				(justify left bottom)
				(hide yes)
			)
		)
		(property "Val" "1u"
			(at 310.515 118.745 90)
			(effects
				(font
					(size 1.27 1.27)
					(thickness 0.15)
				)
				(justify right)
			)
		)
		(property "License" "Apache-2.0"
			(at 332.74 99.06 0)
			(effects
				(font
					(size 1.27 1.27)
					(thickness 0.15)
				)
				(justify left bottom)
				(hide yes)
			)
		)
		(property "Author" "Antmicro"
			(at 335.28 99.06 0)
			(effects
				(font
					(size 1.27 1.27)
					(thickness 0.15)
				)
				(justify left bottom)
				(hide yes)
			)
		)
		(property "Voltage" ""
			(at 337.82 99.06 0)
			(effects
				(font
					(size 1.27 1.27)
				)
				(justify left bottom)
				(hide yes)
			)
		)
		(property "Dielectric" ""
			(at 340.36 99.06 0)
			(effects
				(font
					(size 1.27 1.27)
				)
				(justify left bottom)
				(hide yes)
			)
		)
		(pin "1"
		)
		(pin "2"
		)
		(instances
			(project "k410t-devboard"
				(path ""
					(reference "C348")
					(unit 1)
				)
			)
		)
	)
	(symbol
		(lib_id "antmicroCapacitors0402:C_100n_0402")
		(at 355.6 243.84 90)
		(unit 1)
		(exclude_from_sim no)
		(in_bom yes)
		(on_board yes)
		(dnp no)
		(property "Reference" "C356"
			(at 356.235 239.395 90)
			(effects
				(font
					(size 1.27 1.27)
				)
				(justify right)
			)
		)
		(property "Value" "C_100n_0402"
			(at 365.76 223.52 0)
			(effects
				(font
					(size 1.27 1.27)
					(thickness 0.15)
				)
				(justify left bottom)
				(hide yes)
			)
		)
		(property "Footprint" "antmicro-footprints:C_0402_1005Metric"
			(at 368.3 223.52 0)
			(effects
				(font
					(size 1.27 1.27)
					(thickness 0.15)
				)
				(justify left bottom)
				(hide yes)
			)
		)
		(property "Datasheet" "https://www.murata.com/products/productdetail?partno=GRM155R61H104KE14%23"
			(at 370.84 223.52 0)
			(effects
				(font
					(size 1.27 1.27)
					(thickness 0.15)
				)
				(justify left bottom)
				(hide yes)
			)
		)
		(property "Description" ""
			(at 355.6 243.84 0)
			(effects
				(font
					(size 1.27 1.27)
				)
			)
		)
		(property "Manufacturer" "Murata"
			(at 375.92 223.52 0)
			(effects
				(font
					(size 1.27 1.27)
					(thickness 0.15)
				)
				(justify left bottom)
				(hide yes)
			)
		)
		(property "MPN" "GRM155R61H104KE14D"
			(at 373.38 223.52 0)
			(effects
				(font
					(size 1.27 1.27)
					(thickness 0.15)
				)
				(justify left bottom)
				(hide yes)
			)
		)
		(property "Val" "100n"
			(at 356.235 243.205 90)
			(effects
				(font
					(size 1.27 1.27)
					(thickness 0.15)
				)
				(justify right)
			)
		)
		(property "License" "Apache-2.0"
			(at 378.46 223.52 0)
			(effects
				(font
					(size 1.27 1.27)
					(thickness 0.15)
				)
				(justify left bottom)
				(hide yes)
			)
		)
		(property "Author" "Antmicro"
			(at 381 223.52 0)
			(effects
				(font
					(size 1.27 1.27)
					(thickness 0.15)
				)
				(justify left bottom)
				(hide yes)
			)
		)
		(property "Voltage" "50V"
			(at 383.54 223.52 0)
			(effects
				(font
					(size 1.27 1.27)
				)
				(justify left bottom)
				(hide yes)
			)
		)
		(property "Dielectric" "X5R"
			(at 386.08 223.52 0)
			(effects
				(font
					(size 1.27 1.27)
				)
				(justify left bottom)
				(hide yes)
			)
		)
		(pin "1"
		)
		(pin "2"
		)
		(instances
			(project "k410t-devboard"
				(path ""
					(reference "C356")
					(unit 1)
				)
			)
		)
	)
	(symbol
		(lib_id "antmicroCapacitors0402:C_100n_0402")
		(at 337.82 31.75 180)
		(unit 1)
		(exclude_from_sim no)
		(in_bom yes)
		(on_board yes)
		(dnp no)
		(property "Reference" "C351"
			(at 335.28 28.575 0)
			(effects
				(font
					(size 1.27 1.27)
				)
			)
		)
		(property "Value" "C_100n_0402"
			(at 317.5 21.59 0)
			(effects
				(font
					(size 1.27 1.27)
					(thickness 0.15)
				)
				(justify left bottom)
				(hide yes)
			)
		)
		(property "Footprint" "antmicro-footprints:C_0402_1005Metric"
			(at 317.5 19.05 0)
			(effects
				(font
					(size 1.27 1.27)
					(thickness 0.15)
				)
				(justify left bottom)
				(hide yes)
			)
		)
		(property "Datasheet" "https://www.murata.com/products/productdetail?partno=GRM155R61H104KE14%23"
			(at 317.5 16.51 0)
			(effects
				(font
					(size 1.27 1.27)
					(thickness 0.15)
				)
				(justify left bottom)
				(hide yes)
			)
		)
		(property "Description" ""
			(at 337.82 31.75 0)
			(effects
				(font
					(size 1.27 1.27)
				)
			)
		)
		(property "Manufacturer" "Murata"
			(at 317.5 11.43 0)
			(effects
				(font
					(size 1.27 1.27)
					(thickness 0.15)
				)
				(justify left bottom)
				(hide yes)
			)
		)
		(property "MPN" "GRM155R61H104KE14D"
			(at 317.5 13.97 0)
			(effects
				(font
					(size 1.27 1.27)
					(thickness 0.15)
				)
				(justify left bottom)
				(hide yes)
			)
		)
		(property "Val" "100n"
			(at 335.28 34.925 0)
			(effects
				(font
					(size 1.27 1.27)
					(thickness 0.15)
				)
			)
		)
		(property "License" "Apache-2.0"
			(at 317.5 8.89 0)
			(effects
				(font
					(size 1.27 1.27)
					(thickness 0.15)
				)
				(justify left bottom)
				(hide yes)
			)
		)
		(property "Author" "Antmicro"
			(at 317.5 6.35 0)
			(effects
				(font
					(size 1.27 1.27)
					(thickness 0.15)
				)
				(justify left bottom)
				(hide yes)
			)
		)
		(property "Voltage" "50V"
			(at 317.5 3.81 0)
			(effects
				(font
					(size 1.27 1.27)
				)
				(justify left bottom)
				(hide yes)
			)
		)
		(property "Dielectric" "X5R"
			(at 317.5 1.27 0)
			(effects
				(font
					(size 1.27 1.27)
				)
				(justify left bottom)
				(hide yes)
			)
		)
		(pin "1"
		)
		(pin "2"
		)
		(instances
			(project "k410t-devboard"
				(path ""
					(reference "C351")
					(unit 1)
				)
			)
		)
	)
	(symbol
		(lib_id "antmicroResistors0402:R_47k_0402")
		(at 153.67 52.07 270)
		(mirror x)
		(unit 1)
		(exclude_from_sim no)
		(in_bom yes)
		(on_board yes)
		(dnp no)
		(property "Reference" "R294"
			(at 154.94 48.26 90)
			(effects
				(font
					(size 1.27 1.27)
				)
				(justify left)
			)
		)
		(property "Value" "R_47k_0402"
			(at 140.97 31.75 0)
			(effects
				(font
					(size 1.27 1.27)
					(thickness 0.15)
				)
				(justify left bottom)
				(hide yes)
			)
		)
		(property "Footprint" "antmicro-footprints:R_0402_1005Metric"
			(at 138.43 31.75 0)
			(effects
				(font
					(size 1.27 1.27)
					(thickness 0.15)
				)
				(justify left bottom)
				(hide yes)
			)
		)
		(property "Datasheet" "https://www.bourns.com/docs/product-datasheets/cr.pdf"
			(at 135.89 31.75 0)
			(effects
				(font
					(size 1.27 1.27)
					(thickness 0.15)
				)
				(justify left bottom)
				(hide yes)
			)
		)
		(property "Description" ""
			(at 153.67 52.07 0)
			(effects
				(font
					(size 1.27 1.27)
				)
			)
		)
		(property "Manufacturer" "Bourns"
			(at 130.81 31.75 0)
			(effects
				(font
					(size 1.27 1.27)
					(thickness 0.15)
				)
				(justify left bottom)
				(hide yes)
			)
		)
		(property "MPN" "CR0402-FX-4702GLF"
			(at 133.35 31.75 0)
			(effects
				(font
					(size 1.27 1.27)
					(thickness 0.15)
				)
				(justify left bottom)
				(hide yes)
			)
		)
		(property "Val" "47k"
			(at 154.94 50.8 90)
			(effects
				(font
					(size 1.27 1.27)
					(thickness 0.15)
				)
				(justify left)
			)
		)
		(property "License" "Apache-2.0"
			(at 128.27 31.75 0)
			(effects
				(font
					(size 1.27 1.27)
					(thickness 0.15)
				)
				(justify left bottom)
				(hide yes)
			)
		)
		(property "Author" "Antmicro"
			(at 125.73 31.75 0)
			(effects
				(font
					(size 1.27 1.27)
					(thickness 0.15)
				)
				(justify left bottom)
				(hide yes)
			)
		)
		(property "Tolerance" "1%"
			(at 143.51 31.75 0)
			(effects
				(font
					(size 1.27 1.27)
				)
				(justify left bottom)
				(hide yes)
			)
		)
		(pin "1"
		)
		(pin "2"
		)
		(instances
			(project "k410t-devboard"
				(path ""
					(reference "R294")
					(unit 1)
				)
			)
		)
	)
	(symbol
		(lib_id "antmicroResistors0603:R_0R_22.4A_0603")
		(at 124.46 152.4 0)
		(unit 1)
		(exclude_from_sim no)
		(in_bom yes)
		(on_board yes)
		(dnp no)
		(property "Reference" "R288"
			(at 127 144.78 0)
			(effects
				(font
					(size 1.27 1.27)
				)
			)
		)
		(property "Value" "R_0R_22.4A_0603"
			(at 127 146.05 0)
			(effects
				(font
					(size 1.27 1.27)
					(thickness 0.15)
				)
				(hide yes)
			)
		)
		(property "Footprint" "antmicro-footprints:R_0603_1608Metric"
			(at 147.32 165.1 0)
			(effects
				(font
					(size 1.27 1.27)
					(thickness 0.15)
				)
				(justify left bottom)
				(hide yes)
			)
		)
		(property "Datasheet" "https://fscdn.rohm.com/en/products/databook/datasheet/passive/resistor/chip_resistor/pmr-jpw-e.pdf"
			(at 147.32 167.64 0)
			(effects
				(font
					(size 1.27 1.27)
					(thickness 0.15)
				)
				(justify left bottom)
				(hide yes)
			)
		)
		(property "Description" ""
			(at 124.46 152.4 0)
			(effects
				(font
					(size 1.27 1.27)
				)
			)
		)
		(property "Manufacturer" "ROHM Semiconductor"
			(at 147.32 170.18 0)
			(effects
				(font
					(size 1.27 1.27)
					(thickness 0.15)
				)
				(justify left bottom)
				(hide yes)
			)
		)
		(property "MPN" "PMR03EZPJ000"
			(at 147.32 172.72 0)
			(effects
				(font
					(size 1.27 1.27)
					(thickness 0.15)
				)
				(justify left bottom)
				(hide yes)
			)
		)
		(property "Val" "0R"
			(at 127 147.32 0)
			(effects
				(font
					(size 1.27 1.27)
					(thickness 0.15)
				)
			)
		)
		(property "Author" "Antmicro"
			(at 147.32 175.26 0)
			(effects
				(font
					(size 1.27 1.27)
					(thickness 0.15)
				)
				(justify left bottom)
				(hide yes)
			)
		)
		(property "License" "Apache-2.0"
			(at 147.32 177.8 0)
			(effects
				(font
					(size 1.27 1.27)
					(thickness 0.15)
				)
				(justify left bottom)
				(hide yes)
			)
		)
		(property "Max. Curr." "22.4A"
			(at 127 149.86 0)
			(effects
				(font
					(size 1.27 1.27)
					(thickness 0.15)
				)
			)
		)
		(property "Tolerance" "template_tolerance"
			(at 144.78 162.56 0)
			(effects
				(font
					(size 1.27 1.27)
				)
				(justify left bottom)
				(hide yes)
			)
		)
		(pin "1"
		)
		(pin "2"
		)
		(instances
			(project "k410t-devboard"
				(path ""
					(reference "R288")
					(unit 1)
				)
			)
		)
	)
	(symbol
		(lib_id "antmicroCapacitors0402:C_22p_0402")
		(at 400.05 63.5 90)
		(unit 1)
		(exclude_from_sim no)
		(in_bom yes)
		(on_board yes)
		(dnp no)
		(property "Reference" "C364"
			(at 400.685 59.055 90)
			(effects
				(font
					(size 1.27 1.27)
				)
				(justify right)
			)
		)
		(property "Value" "C_22p_0402"
			(at 410.21 43.18 0)
			(effects
				(font
					(size 1.27 1.27)
					(thickness 0.15)
				)
				(justify left bottom)
				(hide yes)
			)
		)
		(property "Footprint" "antmicro-footprints:C_0402_1005Metric"
			(at 412.75 43.18 0)
			(effects
				(font
					(size 1.27 1.27)
					(thickness 0.15)
				)
				(justify left bottom)
				(hide yes)
			)
		)
		(property "Datasheet" "https://www.yageo.com/en/Chart/Download/pdf/CC0402JRNPO9BN220"
			(at 415.29 43.18 0)
			(effects
				(font
					(size 1.27 1.27)
					(thickness 0.15)
				)
				(justify left bottom)
				(hide yes)
			)
		)
		(property "Description" ""
			(at 400.05 63.5 0)
			(effects
				(font
					(size 1.27 1.27)
				)
			)
		)
		(property "Manufacturer" "YAGEO"
			(at 420.37 43.18 0)
			(effects
				(font
					(size 1.27 1.27)
					(thickness 0.15)
				)
				(justify left bottom)
				(hide yes)
			)
		)
		(property "MPN" "CC0402JRNPO9BN220"
			(at 417.83 43.18 0)
			(effects
				(font
					(size 1.27 1.27)
					(thickness 0.15)
				)
				(justify left bottom)
				(hide yes)
			)
		)
		(property "Val" "22p"
			(at 400.685 62.865 90)
			(effects
				(font
					(size 1.27 1.27)
					(thickness 0.15)
				)
				(justify right)
			)
		)
		(property "License" "Apache-2.0"
			(at 422.91 43.18 0)
			(effects
				(font
					(size 1.27 1.27)
					(thickness 0.15)
				)
				(justify left bottom)
				(hide yes)
			)
		)
		(property "Author" "Antmicro"
			(at 425.45 43.18 0)
			(effects
				(font
					(size 1.27 1.27)
					(thickness 0.15)
				)
				(justify left bottom)
				(hide yes)
			)
		)
		(property "Voltage" ""
			(at 427.99 43.18 0)
			(effects
				(font
					(size 1.27 1.27)
				)
				(justify left bottom)
				(hide yes)
			)
		)
		(property "Dielectric" ""
			(at 430.53 43.18 0)
			(effects
				(font
					(size 1.27 1.27)
				)
				(justify left bottom)
				(hide yes)
			)
		)
		(pin "1"
		)
		(pin "2"
		)
		(instances
			(project "k410t-devboard"
				(path ""
					(reference "C364")
					(unit 1)
				)
			)
		)
	)
	(symbol
		(lib_id "antmicropower:GND")
		(at 309.88 128.27 0)
		(unit 1)
		(exclude_from_sim no)
		(in_bom yes)
		(on_board yes)
		(dnp no)
		(fields_autoplaced yes)
		(property "Reference" "#PWR0416"
			(at 309.88 134.62 0)
			(effects
				(font
					(size 1.27 1.27)
				)
				(hide yes)
			)
		)
		(property "Value" "GND"
			(at 309.88 132.08 0)
			(effects
				(font
					(size 1.27 1.27)
				)
			)
		)
		(property "Footprint" ""
			(at 318.77 135.89 0)
			(effects
				(font
					(size 1.27 1.27)
					(thickness 0.15)
				)
				(justify left bottom)
				(hide yes)
			)
		)
		(property "Datasheet" ""
			(at 318.77 140.97 0)
			(effects
				(font
					(size 1.27 1.27)
					(thickness 0.15)
				)
				(justify left bottom)
				(hide yes)
			)
		)
		(property "Description" ""
			(at 309.88 128.27 0)
			(effects
				(font
					(size 1.27 1.27)
				)
			)
		)
		(property "Author" "Antmicro"
			(at 318.77 135.89 0)
			(effects
				(font
					(size 1.27 1.27)
					(thickness 0.15)
				)
				(justify left bottom)
				(hide yes)
			)
		)
		(property "License" "Apache-2.0"
			(at 318.77 138.43 0)
			(effects
				(font
					(size 1.27 1.27)
					(thickness 0.15)
				)
				(justify left bottom)
				(hide yes)
			)
		)
		(pin "1"
		)
		(instances
			(project "k410t-devboard"
				(path ""
					(reference "#PWR0416")
					(unit 1)
				)
			)
		)
	)
	(symbol
		(lib_id "antmicroCapacitors0603:C_22u_0603")
		(at 119.38 212.09 90)
		(unit 1)
		(exclude_from_sim no)
		(in_bom yes)
		(on_board yes)
		(dnp no)
		(property "Reference" "C331"
			(at 120.015 207.645 90)
			(effects
				(font
					(size 1.27 1.27)
				)
				(justify right)
			)
		)
		(property "Value" "C_22u_0603"
			(at 129.54 191.77 0)
			(effects
				(font
					(size 1.27 1.27)
					(thickness 0.15)
				)
				(justify left bottom)
				(hide yes)
			)
		)
		(property "Footprint" "antmicro-footprints:C_0603_1608Metric"
			(at 132.08 191.77 0)
			(effects
				(font
					(size 1.27 1.27)
					(thickness 0.15)
				)
				(justify left bottom)
				(hide yes)
			)
		)
		(property "Datasheet" "https://www.murata.com/products/productdetail?partno=GRM188R60J226MEA0%23"
			(at 134.62 191.77 0)
			(effects
				(font
					(size 1.27 1.27)
					(thickness 0.15)
				)
				(justify left bottom)
				(hide yes)
			)
		)
		(property "Description" ""
			(at 119.38 212.09 0)
			(effects
				(font
					(size 1.27 1.27)
				)
			)
		)
		(property "Manufacturer" "Murata"
			(at 139.7 191.77 0)
			(effects
				(font
					(size 1.27 1.27)
					(thickness 0.15)
				)
				(justify left bottom)
				(hide yes)
			)
		)
		(property "MPN" "GRM188R60J226MEA0D"
			(at 137.16 191.77 0)
			(effects
				(font
					(size 1.27 1.27)
					(thickness 0.15)
				)
				(justify left bottom)
				(hide yes)
			)
		)
		(property "Val" "22u"
			(at 120.015 211.455 90)
			(effects
				(font
					(size 1.27 1.27)
					(thickness 0.15)
				)
				(justify right)
			)
		)
		(property "License" "Apache-2.0"
			(at 142.24 191.77 0)
			(effects
				(font
					(size 1.27 1.27)
					(thickness 0.15)
				)
				(justify left bottom)
				(hide yes)
			)
		)
		(property "Author" "Antmicro"
			(at 144.78 191.77 0)
			(effects
				(font
					(size 1.27 1.27)
					(thickness 0.15)
				)
				(justify left bottom)
				(hide yes)
			)
		)
		(property "Voltage" ""
			(at 147.32 191.77 0)
			(effects
				(font
					(size 1.27 1.27)
				)
				(justify left bottom)
				(hide yes)
			)
		)
		(property "Dielectric" ""
			(at 149.86 191.77 0)
			(effects
				(font
					(size 1.27 1.27)
				)
				(justify left bottom)
				(hide yes)
			)
		)
		(pin "1"
		)
		(pin "2"
		)
		(instances
			(project "k410t-devboard"
				(path ""
					(reference "C331")
					(unit 1)
				)
			)
		)
	)
	(symbol
		(lib_id "antmicroCapacitors0402:C_10u_0402")
		(at 374.65 223.52 90)
		(unit 1)
		(exclude_from_sim no)
		(in_bom yes)
		(on_board yes)
		(dnp no)
		(property "Reference" "C361"
			(at 375.285 219.075 90)
			(effects
				(font
					(size 1.27 1.27)
				)
				(justify right)
			)
		)
		(property "Value" "C_10u_0402"
			(at 384.81 203.2 0)
			(effects
				(font
					(size 1.27 1.27)
					(thickness 0.15)
				)
				(justify left bottom)
				(hide yes)
			)
		)
		(property "Footprint" "antmicro-footprints:C_0402_1005Metric"
			(at 387.35 203.2 0)
			(effects
				(font
					(size 1.27 1.27)
					(thickness 0.15)
				)
				(justify left bottom)
				(hide yes)
			)
		)
		(property "Datasheet" "https://www.yageo.com/en/Chart/Download/pdf/CC0402MRX5R5BB106"
			(at 389.89 203.2 0)
			(effects
				(font
					(size 1.27 1.27)
					(thickness 0.15)
				)
				(justify left bottom)
				(hide yes)
			)
		)
		(property "Description" ""
			(at 374.65 223.52 0)
			(effects
				(font
					(size 1.27 1.27)
				)
			)
		)
		(property "Manufacturer" "YAGEO"
			(at 394.97 203.2 0)
			(effects
				(font
					(size 1.27 1.27)
					(thickness 0.15)
				)
				(justify left bottom)
				(hide yes)
			)
		)
		(property "MPN" "CC0402MRX5R5BB106"
			(at 392.43 203.2 0)
			(effects
				(font
					(size 1.27 1.27)
					(thickness 0.15)
				)
				(justify left bottom)
				(hide yes)
			)
		)
		(property "Val" "10u"
			(at 375.285 222.885 90)
			(effects
				(font
					(size 1.27 1.27)
					(thickness 0.15)
				)
				(justify right)
			)
		)
		(property "License" "Apache-2.0"
			(at 397.51 203.2 0)
			(effects
				(font
					(size 1.27 1.27)
					(thickness 0.15)
				)
				(justify left bottom)
				(hide yes)
			)
		)
		(property "Author" "Antmicro"
			(at 400.05 203.2 0)
			(effects
				(font
					(size 1.27 1.27)
					(thickness 0.15)
				)
				(justify left bottom)
				(hide yes)
			)
		)
		(property "Voltage" ""
			(at 402.59 203.2 0)
			(effects
				(font
					(size 1.27 1.27)
				)
				(justify left bottom)
				(hide yes)
			)
		)
		(property "Dielectric" ""
			(at 405.13 203.2 0)
			(effects
				(font
					(size 1.27 1.27)
				)
				(justify left bottom)
				(hide yes)
			)
		)
		(pin "1"
		)
		(pin "2"
		)
		(instances
			(project "k410t-devboard"
				(path ""
					(reference "C361")
					(unit 1)
				)
			)
		)
	)
	(symbol
		(lib_id "antmicropower:GND")
		(at 281.94 63.5 0)
		(unit 1)
		(exclude_from_sim no)
		(in_bom yes)
		(on_board yes)
		(dnp no)
		(fields_autoplaced yes)
		(property "Reference" "#PWR0413"
			(at 281.94 69.85 0)
			(effects
				(font
					(size 1.27 1.27)
				)
				(hide yes)
			)
		)
		(property "Value" "GND"
			(at 281.94 67.31 0)
			(effects
				(font
					(size 1.27 1.27)
				)
			)
		)
		(property "Footprint" ""
			(at 290.83 71.12 0)
			(effects
				(font
					(size 1.27 1.27)
					(thickness 0.15)
				)
				(justify left bottom)
				(hide yes)
			)
		)
		(property "Datasheet" ""
			(at 290.83 76.2 0)
			(effects
				(font
					(size 1.27 1.27)
					(thickness 0.15)
				)
				(justify left bottom)
				(hide yes)
			)
		)
		(property "Description" ""
			(at 281.94 63.5 0)
			(effects
				(font
					(size 1.27 1.27)
				)
			)
		)
		(property "Author" "Antmicro"
			(at 290.83 71.12 0)
			(effects
				(font
					(size 1.27 1.27)
					(thickness 0.15)
				)
				(justify left bottom)
				(hide yes)
			)
		)
		(property "License" "Apache-2.0"
			(at 290.83 73.66 0)
			(effects
				(font
					(size 1.27 1.27)
					(thickness 0.15)
				)
				(justify left bottom)
				(hide yes)
			)
		)
		(pin "1"
		)
		(instances
			(project "k410t-devboard"
				(path ""
					(reference "#PWR0413")
					(unit 1)
				)
			)
		)
	)
	(symbol
		(lib_id "antmicroResistors0402:R_0R_0402")
		(at 256.54 236.22 90)
		(unit 1)
		(exclude_from_sim no)
		(in_bom no)
		(on_board yes)
		(dnp yes)
		(property "Reference" "R320"
			(at 258.445 232.41 90)
			(effects
				(font
					(size 1.27 1.27)
				)
				(justify right)
			)
		)
		(property "Value" "R_0R_0402"
			(at 269.24 215.9 0)
			(effects
				(font
					(size 1.27 1.27)
					(thickness 0.15)
				)
				(justify left bottom)
				(hide yes)
			)
		)
		(property "Footprint" "antmicro-footprints:R_0402_1005Metric"
			(at 271.78 215.9 0)
			(effects
				(font
					(size 1.27 1.27)
					(thickness 0.15)
				)
				(justify left bottom)
				(hide yes)
			)
		)
		(property "Datasheet" "https://industrial.panasonic.com/cdbs/www-data/pdf/RDA0000/AOA0000C301.pdf"
			(at 274.32 215.9 0)
			(effects
				(font
					(size 1.27 1.27)
					(thickness 0.15)
				)
				(justify left bottom)
				(hide yes)
			)
		)
		(property "Description" ""
			(at 256.54 236.22 0)
			(effects
				(font
					(size 1.27 1.27)
				)
			)
		)
		(property "Manufacturer" "Panasonic"
			(at 279.4 215.9 0)
			(effects
				(font
					(size 1.27 1.27)
					(thickness 0.15)
				)
				(justify left bottom)
				(hide yes)
			)
		)
		(property "MPN" "ERJ2GE0R00X"
			(at 276.86 215.9 0)
			(effects
				(font
					(size 1.27 1.27)
					(thickness 0.15)
				)
				(justify left bottom)
				(hide yes)
			)
		)
		(property "Val" "0R"
			(at 258.445 234.95 90)
			(effects
				(font
					(size 1.27 1.27)
					(thickness 0.15)
				)
				(justify right)
			)
		)
		(property "DNP" "DNP"
			(at 256.54 231.775 0)
			(effects
				(font
					(size 1.27 1.27)
				)
				(justify right)
			)
		)
		(property "License" "Apache-2.0"
			(at 281.94 215.9 0)
			(effects
				(font
					(size 1.27 1.27)
					(thickness 0.15)
				)
				(justify left bottom)
				(hide yes)
			)
		)
		(property "Author" "Antmicro"
			(at 284.48 215.9 0)
			(effects
				(font
					(size 1.27 1.27)
					(thickness 0.15)
				)
				(justify left bottom)
				(hide yes)
			)
		)
		(property "Tolerance" "~"
			(at 266.7 215.9 0)
			(effects
				(font
					(size 1.27 1.27)
				)
				(justify left bottom)
				(hide yes)
			)
		)
		(property "Current" "1A"
			(at 258.445 237.4899 90)
			(effects
				(font
					(size 1.27 1.27)
					(thickness 0.15)
				)
				(justify right)
				(hide yes)
			)
		)
		(pin "1"
		)
		(pin "2"
		)
		(instances
			(project "k410t-devboard"
				(path ""
					(reference "R320")
					(unit 1)
				)
			)
		)
	)
	(symbol
		(lib_id "antmicroPMICPowerSequencers:MAX16150A_SOT")
		(at 121.92 35.56 0)
		(unit 1)
		(exclude_from_sim no)
		(in_bom yes)
		(on_board yes)
		(dnp no)
		(property "Reference" "U33"
			(at 130.81 29.21 0)
			(effects
				(font
					(size 1.27 1.27)
				)
			)
		)
		(property "Value" "MAX16150A_SOT"
			(at 130.81 44.45 0)
			(effects
				(font
					(size 1.27 1.27)
					(thickness 0.15)
				)
				(hide yes)
			)
		)
		(property "Footprint" "antmicro-footprints:SOT-23-6"
			(at 153.67 44.45 0)
			(effects
				(font
					(size 1.27 1.27)
					(thickness 0.15)
				)
				(justify left bottom)
				(hide yes)
			)
		)
		(property "Datasheet" "https://datasheets.maximintegrated.com/en/ds/MAX16150.pdf"
			(at 153.67 46.99 0)
			(effects
				(font
					(size 1.27 1.27)
					(thickness 0.15)
				)
				(justify left bottom)
				(hide yes)
			)
		)
		(property "Description" ""
			(at 121.92 35.56 0)
			(effects
				(font
					(size 1.27 1.27)
				)
			)
		)
		(property "Manufacturer" "Maxim Integrated Products"
			(at 153.67 49.53 0)
			(effects
				(font
					(size 1.27 1.27)
					(thickness 0.15)
				)
				(justify left bottom)
				(hide yes)
			)
		)
		(property "MPN" "MAX16150AUT+T"
			(at 130.81 31.75 0)
			(effects
				(font
					(size 1.27 1.27)
					(thickness 0.15)
				)
			)
		)
		(property "License" "Apache-2.0"
			(at 153.67 54.61 0)
			(effects
				(font
					(size 1.27 1.27)
					(thickness 0.15)
				)
				(justify left bottom)
				(hide yes)
			)
		)
		(property "Author" "Antmicro"
			(at 153.67 57.15 0)
			(effects
				(font
					(size 1.27 1.27)
					(thickness 0.15)
				)
				(justify left bottom)
				(hide yes)
			)
		)
		(pin "1"
		)
		(pin "2"
		)
		(pin "3"
		)
		(pin "4"
		)
		(pin "5"
		)
		(pin "6"
		)
		(instances
			(project "k410t-devboard"
				(path ""
					(reference "U33")
					(unit 1)
				)
			)
		)
	)
	(symbol
		(lib_id "antmicropower:+3V3_AON")
		(at 121.92 16.51 0)
		(unit 1)
		(exclude_from_sim no)
		(in_bom yes)
		(on_board yes)
		(dnp no)
		(property "Reference" "#PWR0473"
			(at 121.92 20.32 0)
			(effects
				(font
					(size 1.27 1.27)
				)
				(hide yes)
			)
		)
		(property "Value" "+3V3_AON"
			(at 121.92 13.97 0)
			(effects
				(font
					(size 1.27 1.27)
				)
				(justify bottom)
			)
		)
		(property "Footprint" ""
			(at 121.92 16.51 0)
			(effects
				(font
					(size 1.27 1.27)
				)
				(hide yes)
			)
		)
		(property "Datasheet" ""
			(at 121.92 16.51 0)
			(effects
				(font
					(size 1.27 1.27)
				)
				(hide yes)
			)
		)
		(property "Description" ""
			(at 121.92 16.51 0)
			(effects
				(font
					(size 1.27 1.27)
				)
			)
		)
		(pin "1"
		)
		(instances
			(project "k410t-devboard"
				(path ""
					(reference "#PWR0473")
					(unit 1)
				)
			)
		)
	)
	(symbol
		(lib_id "k410t-devboard:Net-Tie_2")
		(at 200.66 91.44 90)
		(unit 1)
		(exclude_from_sim no)
		(in_bom yes)
		(on_board yes)
		(dnp no)
		(fields_autoplaced yes)
		(property "Reference" "NT33"
			(at 199.39 91.44 0)
			(effects
				(font
					(size 1.27 1.27)
				)
				(hide yes)
			)
		)
		(property "Value" "Net-Tie_2"
			(at 201.93 89.5349 90)
			(effects
				(font
					(size 1.27 1.27)
					(thickness 0.15)
				)
				(justify right)
				(hide yes)
			)
		)
		(property "Footprint" "antmicro-footprints:NetTie-2_SMD_Pad0.127mm"
			(at 205.74 69.85 0)
			(effects
				(font
					(size 1.27 1.27)
					(thickness 0.15)
				)
				(justify left bottom)
				(hide yes)
			)
		)
		(property "Datasheet" ""
			(at 208.28 69.85 0)
			(effects
				(font
					(size 1.27 1.27)
					(thickness 0.15)
				)
				(justify left bottom)
				(hide yes)
			)
		)
		(property "Description" ""
			(at 200.66 91.44 0)
			(effects
				(font
					(size 1.27 1.27)
				)
			)
		)
		(property "MPN" ""
			(at 209.55 69.85 0)
			(effects
				(font
					(size 1.27 1.27)
				)
				(justify left)
				(hide yes)
			)
		)
		(property "Manufacturer" ""
			(at 212.09 69.85 0)
			(effects
				(font
					(size 1.27 1.27)
				)
				(justify left)
				(hide yes)
			)
		)
		(property "Author" "Antmicro"
			(at 215.9 69.85 0)
			(effects
				(font
					(size 1.27 1.27)
					(thickness 0.15)
				)
				(justify left bottom)
				(hide yes)
			)
		)
		(property "License" "Apache-2.0"
			(at 218.44 69.85 0)
			(effects
				(font
					(size 1.27 1.27)
					(thickness 0.15)
				)
				(justify left bottom)
				(hide yes)
			)
		)
		(pin "1"
		)
		(pin "2"
		)
		(instances
			(project "k410t-devboard"
				(path ""
					(reference "NT33")
					(unit 1)
				)
			)
		)
	)
	(symbol
		(lib_id "antmicropower:VDC")
		(at 49.53 181.61 0)
		(unit 1)
		(exclude_from_sim no)
		(in_bom yes)
		(on_board yes)
		(dnp no)
		(fields_autoplaced yes)
		(property "Reference" "#PWR0333"
			(at 49.53 184.15 0)
			(effects
				(font
					(size 1.27 1.27)
				)
				(hide yes)
			)
		)
		(property "Value" "VDC"
			(at 49.53 176.53 0)
			(effects
				(font
					(size 1.27 1.27)
				)
			)
		)
		(property "Footprint" ""
			(at 49.53 181.61 0)
			(effects
				(font
					(size 1.27 1.27)
				)
				(hide yes)
			)
		)
		(property "Datasheet" ""
			(at 49.53 181.61 0)
			(effects
				(font
					(size 1.27 1.27)
				)
				(hide yes)
			)
		)
		(property "Description" ""
			(at 49.53 181.61 0)
			(effects
				(font
					(size 1.27 1.27)
				)
			)
		)
		(pin "1"
		)
		(instances
			(project "k410t-devboard"
				(path ""
					(reference "#PWR0333")
					(unit 1)
				)
			)
		)
	)
	(symbol
		(lib_id "antmicropower:GND")
		(at 350.52 123.19 0)
		(unit 1)
		(exclude_from_sim no)
		(in_bom yes)
		(on_board yes)
		(dnp no)
		(fields_autoplaced yes)
		(property "Reference" "#PWR0434"
			(at 350.52 129.54 0)
			(effects
				(font
					(size 1.27 1.27)
				)
				(hide yes)
			)
		)
		(property "Value" "GND"
			(at 350.52 127 0)
			(effects
				(font
					(size 1.27 1.27)
				)
			)
		)
		(property "Footprint" ""
			(at 359.41 130.81 0)
			(effects
				(font
					(size 1.27 1.27)
					(thickness 0.15)
				)
				(justify left bottom)
				(hide yes)
			)
		)
		(property "Datasheet" ""
			(at 359.41 135.89 0)
			(effects
				(font
					(size 1.27 1.27)
					(thickness 0.15)
				)
				(justify left bottom)
				(hide yes)
			)
		)
		(property "Description" ""
			(at 350.52 123.19 0)
			(effects
				(font
					(size 1.27 1.27)
				)
			)
		)
		(property "Author" "Antmicro"
			(at 359.41 130.81 0)
			(effects
				(font
					(size 1.27 1.27)
					(thickness 0.15)
				)
				(justify left bottom)
				(hide yes)
			)
		)
		(property "License" "Apache-2.0"
			(at 359.41 133.35 0)
			(effects
				(font
					(size 1.27 1.27)
					(thickness 0.15)
				)
				(justify left bottom)
				(hide yes)
			)
		)
		(pin "1"
		)
		(instances
			(project "k410t-devboard"
				(path ""
					(reference "#PWR0434")
					(unit 1)
				)
			)
		)
	)
	(symbol
		(lib_id "antmicropower:GND")
		(at 140.97 40.64 0)
		(unit 1)
		(exclude_from_sim no)
		(in_bom yes)
		(on_board yes)
		(dnp no)
		(property "Reference" "#PWR0392"
			(at 140.97 46.99 0)
			(effects
				(font
					(size 1.27 1.27)
				)
				(hide yes)
			)
		)
		(property "Value" "GND"
			(at 143.51 41.91 0)
			(effects
				(font
					(size 1.27 1.27)
				)
				(justify bottom)
			)
		)
		(property "Footprint" ""
			(at 149.86 48.26 0)
			(effects
				(font
					(size 1.27 1.27)
					(thickness 0.15)
				)
				(justify left bottom)
				(hide yes)
			)
		)
		(property "Datasheet" ""
			(at 149.86 53.34 0)
			(effects
				(font
					(size 1.27 1.27)
					(thickness 0.15)
				)
				(justify left bottom)
				(hide yes)
			)
		)
		(property "Description" ""
			(at 140.97 40.64 0)
			(effects
				(font
					(size 1.27 1.27)
				)
			)
		)
		(property "Author" "Antmicro"
			(at 149.86 48.26 0)
			(effects
				(font
					(size 1.27 1.27)
					(thickness 0.15)
				)
				(justify left bottom)
				(hide yes)
			)
		)
		(property "License" "Apache-2.0"
			(at 149.86 50.8 0)
			(effects
				(font
					(size 1.27 1.27)
					(thickness 0.15)
				)
				(justify left bottom)
				(hide yes)
			)
		)
		(pin "1"
		)
		(instances
			(project "k410t-devboard"
				(path ""
					(reference "#PWR0392")
					(unit 1)
				)
			)
		)
	)
	(symbol
		(lib_id "antmicroCapacitors0402:C_100n_0402")
		(at 393.7 214.63 90)
		(unit 1)
		(exclude_from_sim no)
		(in_bom yes)
		(on_board yes)
		(dnp no)
		(property "Reference" "C399"
			(at 394.335 210.185 90)
			(effects
				(font
					(size 1.27 1.27)
				)
				(justify right)
			)
		)
		(property "Value" "C_100n_0402"
			(at 403.86 194.31 0)
			(effects
				(font
					(size 1.27 1.27)
					(thickness 0.15)
				)
				(justify left bottom)
				(hide yes)
			)
		)
		(property "Footprint" "antmicro-footprints:C_0402_1005Metric"
			(at 406.4 194.31 0)
			(effects
				(font
					(size 1.27 1.27)
					(thickness 0.15)
				)
				(justify left bottom)
				(hide yes)
			)
		)
		(property "Datasheet" "https://www.murata.com/products/productdetail?partno=GRM155R61H104KE14%23"
			(at 408.94 194.31 0)
			(effects
				(font
					(size 1.27 1.27)
					(thickness 0.15)
				)
				(justify left bottom)
				(hide yes)
			)
		)
		(property "Description" ""
			(at 393.7 214.63 0)
			(effects
				(font
					(size 1.27 1.27)
				)
			)
		)
		(property "Manufacturer" "Murata"
			(at 414.02 194.31 0)
			(effects
				(font
					(size 1.27 1.27)
					(thickness 0.15)
				)
				(justify left bottom)
				(hide yes)
			)
		)
		(property "MPN" "GRM155R61H104KE14D"
			(at 411.48 194.31 0)
			(effects
				(font
					(size 1.27 1.27)
					(thickness 0.15)
				)
				(justify left bottom)
				(hide yes)
			)
		)
		(property "Val" "100n"
			(at 394.335 213.995 90)
			(effects
				(font
					(size 1.27 1.27)
					(thickness 0.15)
				)
				(justify right)
			)
		)
		(property "License" "Apache-2.0"
			(at 416.56 194.31 0)
			(effects
				(font
					(size 1.27 1.27)
					(thickness 0.15)
				)
				(justify left bottom)
				(hide yes)
			)
		)
		(property "Author" "Antmicro"
			(at 419.1 194.31 0)
			(effects
				(font
					(size 1.27 1.27)
					(thickness 0.15)
				)
				(justify left bottom)
				(hide yes)
			)
		)
		(property "Voltage" "50V"
			(at 421.64 194.31 0)
			(effects
				(font
					(size 1.27 1.27)
				)
				(justify left bottom)
				(hide yes)
			)
		)
		(property "Dielectric" "X5R"
			(at 424.18 194.31 0)
			(effects
				(font
					(size 1.27 1.27)
				)
				(justify left bottom)
				(hide yes)
			)
		)
		(pin "1"
		)
		(pin "2"
		)
		(instances
			(project "k410t-devboard"
				(path ""
					(reference "C399")
					(unit 1)
				)
			)
		)
	)
	(symbol
		(lib_id "antmicropower:+0V675_VREF")
		(at 360.68 234.95 0)
		(unit 1)
		(exclude_from_sim no)
		(in_bom yes)
		(on_board yes)
		(dnp no)
		(property "Reference" "#PWR0400"
			(at 360.68 238.76 0)
			(effects
				(font
					(size 1.27 1.27)
				)
				(hide yes)
			)
		)
		(property "Value" "+0V675_VREF"
			(at 360.68 231.394 0)
			(effects
				(font
					(size 1.27 1.27)
				)
			)
		)
		(property "Footprint" ""
			(at 360.68 234.95 0)
			(effects
				(font
					(size 1.27 1.27)
				)
				(hide yes)
			)
		)
		(property "Datasheet" ""
			(at 360.68 234.95 0)
			(effects
				(font
					(size 1.27 1.27)
				)
				(hide yes)
			)
		)
		(property "Description" ""
			(at 360.68 234.95 0)
			(effects
				(font
					(size 1.27 1.27)
				)
			)
		)
		(pin "1"
		)
		(instances
			(project "k410t-devboard"
				(path ""
					(reference "#PWR0400")
					(unit 1)
				)
			)
		)
	)
	(symbol
		(lib_id "antmicropower:+1V35")
		(at 403.86 228.6 0)
		(unit 1)
		(exclude_from_sim no)
		(in_bom yes)
		(on_board yes)
		(dnp no)
		(property "Reference" "#PWR0497"
			(at 403.86 232.41 0)
			(effects
				(font
					(size 1.27 1.27)
				)
				(hide yes)
			)
		)
		(property "Value" "+1V35"
			(at 403.86 225.044 0)
			(effects
				(font
					(size 1.27 1.27)
				)
			)
		)
		(property "Footprint" ""
			(at 403.86 228.6 0)
			(effects
				(font
					(size 1.27 1.27)
				)
				(hide yes)
			)
		)
		(property "Datasheet" ""
			(at 403.86 228.6 0)
			(effects
				(font
					(size 1.27 1.27)
				)
				(hide yes)
			)
		)
		(property "Description" ""
			(at 403.86 228.6 0)
			(effects
				(font
					(size 1.27 1.27)
				)
			)
		)
		(pin "1"
		)
		(instances
			(project "k410t-devboard"
				(path ""
					(reference "#PWR0497")
					(unit 1)
				)
			)
		)
	)
	(symbol
		(lib_id "antmicropower:GND")
		(at 384.81 242.57 0)
		(mirror y)
		(unit 1)
		(exclude_from_sim no)
		(in_bom yes)
		(on_board yes)
		(dnp no)
		(property "Reference" "#PWR0453"
			(at 384.81 248.92 0)
			(effects
				(font
					(size 1.27 1.27)
				)
				(hide yes)
			)
		)
		(property "Value" "GND"
			(at 384.81 246.38 0)
			(effects
				(font
					(size 1.27 1.27)
				)
			)
		)
		(property "Footprint" ""
			(at 375.92 250.19 0)
			(effects
				(font
					(size 1.27 1.27)
					(thickness 0.15)
				)
				(justify left bottom)
				(hide yes)
			)
		)
		(property "Datasheet" ""
			(at 375.92 255.27 0)
			(effects
				(font
					(size 1.27 1.27)
					(thickness 0.15)
				)
				(justify left bottom)
				(hide yes)
			)
		)
		(property "Description" ""
			(at 384.81 242.57 0)
			(effects
				(font
					(size 1.27 1.27)
				)
			)
		)
		(property "Author" "Antmicro"
			(at 375.92 250.19 0)
			(effects
				(font
					(size 1.27 1.27)
					(thickness 0.15)
				)
				(justify left bottom)
				(hide yes)
			)
		)
		(property "License" "Apache-2.0"
			(at 375.92 252.73 0)
			(effects
				(font
					(size 1.27 1.27)
					(thickness 0.15)
				)
				(justify left bottom)
				(hide yes)
			)
		)
		(pin "1"
		)
		(instances
			(project "k410t-devboard"
				(path ""
					(reference "#PWR0453")
					(unit 1)
				)
			)
		)
	)
	(symbol
		(lib_id "antmicroCapacitors0603:C_1u_25V_0603")
		(at 21.59 45.72 90)
		(mirror x)
		(unit 1)
		(exclude_from_sim no)
		(in_bom yes)
		(on_board yes)
		(dnp no)
		(property "Reference" "C314"
			(at 22.225 46.355 90)
			(effects
				(font
					(size 1.27 1.27)
				)
				(justify right)
			)
		)
		(property "Value" "C_1u_25V_0603"
			(at 31.75 66.04 0)
			(effects
				(font
					(size 1.27 1.27)
					(thickness 0.15)
				)
				(justify left bottom)
				(hide yes)
			)
		)
		(property "Footprint" "antmicro-footprints:C_0603_1608Metric"
			(at 34.29 66.04 0)
			(effects
				(font
					(size 1.27 1.27)
					(thickness 0.15)
				)
				(justify left bottom)
				(hide yes)
			)
		)
		(property "Datasheet" "https://product.samsungsem.com/mlcc/CL10A105KA8NNN.do"
			(at 36.83 66.04 0)
			(effects
				(font
					(size 1.27 1.27)
					(thickness 0.15)
				)
				(justify left bottom)
				(hide yes)
			)
		)
		(property "Description" ""
			(at 21.59 45.72 0)
			(effects
				(font
					(size 1.27 1.27)
				)
			)
		)
		(property "Manufacturer" "Samsung Electro-Mechanics"
			(at 41.91 66.04 0)
			(effects
				(font
					(size 1.27 1.27)
					(thickness 0.15)
				)
				(justify left bottom)
				(hide yes)
			)
		)
		(property "MPN" "CL10A105KA8NNNC"
			(at 39.37 66.04 0)
			(effects
				(font
					(size 1.27 1.27)
					(thickness 0.15)
				)
				(justify left bottom)
				(hide yes)
			)
		)
		(property "Val" "1u"
			(at 22.225 50.165 90)
			(effects
				(font
					(size 1.27 1.27)
					(thickness 0.15)
				)
				(justify right)
			)
		)
		(property "License" "Apache-2.0"
			(at 44.45 66.04 0)
			(effects
				(font
					(size 1.27 1.27)
					(thickness 0.15)
				)
				(justify left bottom)
				(hide yes)
			)
		)
		(property "Author" "Antmicro"
			(at 46.99 66.04 0)
			(effects
				(font
					(size 1.27 1.27)
					(thickness 0.15)
				)
				(justify left bottom)
				(hide yes)
			)
		)
		(property "Voltage" "25V"
			(at 49.53 66.04 0)
			(effects
				(font
					(size 1.27 1.27)
				)
				(justify left bottom)
				(hide yes)
			)
		)
		(property "Dielectric" ""
			(at 52.07 66.04 0)
			(effects
				(font
					(size 1.27 1.27)
				)
				(justify left bottom)
				(hide yes)
			)
		)
		(pin "1"
		)
		(pin "2"
		)
		(instances
			(project "k410t-devboard"
				(path ""
					(reference "C314")
					(unit 1)
				)
			)
		)
	)
	(symbol
		(lib_id "antmicroResistors0603:R_0R_22.4A_0603")
		(at 124.46 204.47 0)
		(unit 1)
		(exclude_from_sim no)
		(in_bom yes)
		(on_board yes)
		(dnp no)
		(property "Reference" "R290"
			(at 127 196.85 0)
			(effects
				(font
					(size 1.27 1.27)
				)
			)
		)
		(property "Value" "R_0R_22.4A_0603"
			(at 147.32 212.09 0)
			(effects
				(font
					(size 1.27 1.27)
					(thickness 0.15)
				)
				(justify left bottom)
				(hide yes)
			)
		)
		(property "Footprint" "antmicro-footprints:R_0603_1608Metric"
			(at 147.32 217.17 0)
			(effects
				(font
					(size 1.27 1.27)
					(thickness 0.15)
				)
				(justify left bottom)
				(hide yes)
			)
		)
		(property "Datasheet" "https://fscdn.rohm.com/en/products/databook/datasheet/passive/resistor/chip_resistor/pmr-jpw-e.pdf"
			(at 147.32 219.71 0)
			(effects
				(font
					(size 1.27 1.27)
					(thickness 0.15)
				)
				(justify left bottom)
				(hide yes)
			)
		)
		(property "Description" ""
			(at 124.46 204.47 0)
			(effects
				(font
					(size 1.27 1.27)
				)
			)
		)
		(property "Manufacturer" "ROHM Semiconductor"
			(at 147.32 222.25 0)
			(effects
				(font
					(size 1.27 1.27)
					(thickness 0.15)
				)
				(justify left bottom)
				(hide yes)
			)
		)
		(property "MPN" "PMR03EZPJ000"
			(at 147.32 224.79 0)
			(effects
				(font
					(size 1.27 1.27)
					(thickness 0.15)
				)
				(justify left bottom)
				(hide yes)
			)
		)
		(property "Val" "0R"
			(at 127 199.39 0)
			(effects
				(font
					(size 1.27 1.27)
					(thickness 0.15)
				)
			)
		)
		(property "Author" "Antmicro"
			(at 147.32 227.33 0)
			(effects
				(font
					(size 1.27 1.27)
					(thickness 0.15)
				)
				(justify left bottom)
				(hide yes)
			)
		)
		(property "License" "Apache-2.0"
			(at 147.32 229.87 0)
			(effects
				(font
					(size 1.27 1.27)
					(thickness 0.15)
				)
				(justify left bottom)
				(hide yes)
			)
		)
		(property "Max. Curr." "22.4A"
			(at 127 201.93 0)
			(effects
				(font
					(size 1.27 1.27)
					(thickness 0.15)
				)
			)
		)
		(property "Tolerance" "template_tolerance"
			(at 144.78 214.63 0)
			(effects
				(font
					(size 1.27 1.27)
				)
				(justify left bottom)
				(hide yes)
			)
		)
		(pin "1"
		)
		(pin "2"
		)
		(instances
			(project "k410t-devboard"
				(path ""
					(reference "R290")
					(unit 1)
				)
			)
		)
	)
	(symbol
		(lib_id "antmicropower:VDC")
		(at 281.94 29.21 0)
		(unit 1)
		(exclude_from_sim no)
		(in_bom yes)
		(on_board yes)
		(dnp no)
		(fields_autoplaced yes)
		(property "Reference" "#PWR0384"
			(at 281.94 31.75 0)
			(effects
				(font
					(size 1.27 1.27)
				)
				(hide yes)
			)
		)
		(property "Value" "VDC"
			(at 281.94 24.13 0)
			(effects
				(font
					(size 1.27 1.27)
				)
			)
		)
		(property "Footprint" ""
			(at 281.94 29.21 0)
			(effects
				(font
					(size 1.27 1.27)
				)
				(hide yes)
			)
		)
		(property "Datasheet" ""
			(at 281.94 29.21 0)
			(effects
				(font
					(size 1.27 1.27)
				)
				(hide yes)
			)
		)
		(property "Description" ""
			(at 281.94 29.21 0)
			(effects
				(font
					(size 1.27 1.27)
				)
			)
		)
		(pin "1"
		)
		(instances
			(project "k410t-devboard"
				(path ""
					(reference "#PWR0384")
					(unit 1)
				)
			)
		)
	)
	(symbol
		(lib_id "antmicroLogicBuffersDriversReceiversTransceivers:SN74LVC1G125_SOT")
		(at 161.29 31.75 0)
		(unit 1)
		(exclude_from_sim no)
		(in_bom yes)
		(on_board yes)
		(dnp no)
		(fields_autoplaced yes)
		(property "Reference" "U35"
			(at 170.18 24.13 0)
			(effects
				(font
					(size 1.27 1.27)
				)
			)
		)
		(property "Value" "SN74LVC1G125_SOT"
			(at 170.18 26.67 0)
			(effects
				(font
					(size 1.27 1.27)
					(thickness 0.15)
				)
				(hide yes)
			)
		)
		(property "Footprint" "antmicro-footprints:SOT-753"
			(at 193.04 41.91 0)
			(effects
				(font
					(size 1.27 1.27)
					(thickness 0.15)
				)
				(justify left bottom)
				(hide yes)
			)
		)
		(property "Datasheet" "http://www.ti.com/general/docs/suppproductinfo.tsp?distId=10&gotoUrl=http%3A%2F%2Fwww.ti.com%2Flit%2Fgpn%2Fsn74lvc1g125"
			(at 193.04 44.45 0)
			(effects
				(font
					(size 1.27 1.27)
					(thickness 0.15)
				)
				(justify left bottom)
				(hide yes)
			)
		)
		(property "Description" ""
			(at 161.29 31.75 0)
			(effects
				(font
					(size 1.27 1.27)
				)
			)
		)
		(property "MPN" "SN74LVC1G125DBVR"
			(at 170.18 26.67 0)
			(effects
				(font
					(size 1.27 1.27)
					(thickness 0.15)
				)
			)
		)
		(property "Manufacturer" "Texas Instruments"
			(at 193.04 49.53 0)
			(effects
				(font
					(size 1.27 1.27)
					(thickness 0.15)
				)
				(justify left bottom)
				(hide yes)
			)
		)
		(property "Author" "Antmicro"
			(at 193.04 52.07 0)
			(effects
				(font
					(size 1.27 1.27)
					(thickness 0.15)
				)
				(justify left bottom)
				(hide yes)
			)
		)
		(property "License" "Apache-2.0"
			(at 193.04 54.61 0)
			(effects
				(font
					(size 1.27 1.27)
					(thickness 0.15)
				)
				(justify left bottom)
				(hide yes)
			)
		)
		(pin "1"
		)
		(pin "2"
		)
		(pin "3"
		)
		(pin "4"
		)
		(pin "5"
		)
		(instances
			(project "k410t-devboard"
				(path ""
					(reference "U35")
					(unit 1)
				)
			)
		)
	)
	(symbol
		(lib_id "antmicroCapacitors0402:C_10u_0402")
		(at 364.49 223.52 90)
		(unit 1)
		(exclude_from_sim no)
		(in_bom yes)
		(on_board yes)
		(dnp no)
		(property "Reference" "C358"
			(at 365.125 219.075 90)
			(effects
				(font
					(size 1.27 1.27)
				)
				(justify right)
			)
		)
		(property "Value" "C_10u_0402"
			(at 374.65 203.2 0)
			(effects
				(font
					(size 1.27 1.27)
					(thickness 0.15)
				)
				(justify left bottom)
				(hide yes)
			)
		)
		(property "Footprint" "antmicro-footprints:C_0402_1005Metric"
			(at 377.19 203.2 0)
			(effects
				(font
					(size 1.27 1.27)
					(thickness 0.15)
				)
				(justify left bottom)
				(hide yes)
			)
		)
		(property "Datasheet" "https://www.yageo.com/en/Chart/Download/pdf/CC0402MRX5R5BB106"
			(at 379.73 203.2 0)
			(effects
				(font
					(size 1.27 1.27)
					(thickness 0.15)
				)
				(justify left bottom)
				(hide yes)
			)
		)
		(property "Description" ""
			(at 364.49 223.52 0)
			(effects
				(font
					(size 1.27 1.27)
				)
			)
		)
		(property "Manufacturer" "YAGEO"
			(at 384.81 203.2 0)
			(effects
				(font
					(size 1.27 1.27)
					(thickness 0.15)
				)
				(justify left bottom)
				(hide yes)
			)
		)
		(property "MPN" "CC0402MRX5R5BB106"
			(at 382.27 203.2 0)
			(effects
				(font
					(size 1.27 1.27)
					(thickness 0.15)
				)
				(justify left bottom)
				(hide yes)
			)
		)
		(property "Val" "10u"
			(at 365.125 222.885 90)
			(effects
				(font
					(size 1.27 1.27)
					(thickness 0.15)
				)
				(justify right)
			)
		)
		(property "License" "Apache-2.0"
			(at 387.35 203.2 0)
			(effects
				(font
					(size 1.27 1.27)
					(thickness 0.15)
				)
				(justify left bottom)
				(hide yes)
			)
		)
		(property "Author" "Antmicro"
			(at 389.89 203.2 0)
			(effects
				(font
					(size 1.27 1.27)
					(thickness 0.15)
				)
				(justify left bottom)
				(hide yes)
			)
		)
		(property "Voltage" ""
			(at 392.43 203.2 0)
			(effects
				(font
					(size 1.27 1.27)
				)
				(justify left bottom)
				(hide yes)
			)
		)
		(property "Dielectric" ""
			(at 394.97 203.2 0)
			(effects
				(font
					(size 1.27 1.27)
				)
				(justify left bottom)
				(hide yes)
			)
		)
		(pin "1"
		)
		(pin "2"
		)
		(instances
			(project "k410t-devboard"
				(path ""
					(reference "C358")
					(unit 1)
				)
			)
		)
	)
	(symbol
		(lib_id "antmicroCapacitors0603:C_22u_0603")
		(at 354.33 53.34 90)
		(unit 1)
		(exclude_from_sim no)
		(in_bom yes)
		(on_board yes)
		(dnp no)
		(property "Reference" "C357"
			(at 354.965 48.895 90)
			(effects
				(font
					(size 1.27 1.27)
				)
				(justify right)
			)
		)
		(property "Value" "C_22u_0603"
			(at 364.49 33.02 0)
			(effects
				(font
					(size 1.27 1.27)
					(thickness 0.15)
				)
				(justify left bottom)
				(hide yes)
			)
		)
		(property "Footprint" "antmicro-footprints:C_0603_1608Metric"
			(at 367.03 33.02 0)
			(effects
				(font
					(size 1.27 1.27)
					(thickness 0.15)
				)
				(justify left bottom)
				(hide yes)
			)
		)
		(property "Datasheet" "https://www.murata.com/products/productdetail?partno=GRM188R60J226MEA0%23"
			(at 369.57 33.02 0)
			(effects
				(font
					(size 1.27 1.27)
					(thickness 0.15)
				)
				(justify left bottom)
				(hide yes)
			)
		)
		(property "Description" ""
			(at 354.33 53.34 0)
			(effects
				(font
					(size 1.27 1.27)
				)
			)
		)
		(property "Manufacturer" "Murata"
			(at 374.65 33.02 0)
			(effects
				(font
					(size 1.27 1.27)
					(thickness 0.15)
				)
				(justify left bottom)
				(hide yes)
			)
		)
		(property "MPN" "GRM188R60J226MEA0D"
			(at 372.11 33.02 0)
			(effects
				(font
					(size 1.27 1.27)
					(thickness 0.15)
				)
				(justify left bottom)
				(hide yes)
			)
		)
		(property "Val" "22u"
			(at 354.965 52.705 90)
			(effects
				(font
					(size 1.27 1.27)
					(thickness 0.15)
				)
				(justify right)
			)
		)
		(property "License" "Apache-2.0"
			(at 377.19 33.02 0)
			(effects
				(font
					(size 1.27 1.27)
					(thickness 0.15)
				)
				(justify left bottom)
				(hide yes)
			)
		)
		(property "Author" "Antmicro"
			(at 379.73 33.02 0)
			(effects
				(font
					(size 1.27 1.27)
					(thickness 0.15)
				)
				(justify left bottom)
				(hide yes)
			)
		)
		(property "Voltage" ""
			(at 382.27 33.02 0)
			(effects
				(font
					(size 1.27 1.27)
				)
				(justify left bottom)
				(hide yes)
			)
		)
		(property "Dielectric" ""
			(at 384.81 33.02 0)
			(effects
				(font
					(size 1.27 1.27)
				)
				(justify left bottom)
				(hide yes)
			)
		)
		(pin "1"
		)
		(pin "2"
		)
		(instances
			(project "k410t-devboard"
				(path ""
					(reference "C357")
					(unit 1)
				)
			)
		)
	)
	(symbol
		(lib_id "antmicroResistors0402:R_0R_0402")
		(at 204.47 240.03 90)
		(unit 1)
		(exclude_from_sim no)
		(in_bom no)
		(on_board yes)
		(dnp yes)
		(property "Reference" "R307"
			(at 207.01 236.22 90)
			(effects
				(font
					(size 1.27 1.27)
				)
				(justify right)
			)
		)
		(property "Value" "R_0R_0402"
			(at 217.17 219.71 0)
			(effects
				(font
					(size 1.27 1.27)
					(thickness 0.15)
				)
				(justify left bottom)
				(hide yes)
			)
		)
		(property "Footprint" "antmicro-footprints:R_0402_1005Metric"
			(at 219.71 219.71 0)
			(effects
				(font
					(size 1.27 1.27)
					(thickness 0.15)
				)
				(justify left bottom)
				(hide yes)
			)
		)
		(property "Datasheet" "https://industrial.panasonic.com/cdbs/www-data/pdf/RDA0000/AOA0000C301.pdf"
			(at 222.25 219.71 0)
			(effects
				(font
					(size 1.27 1.27)
					(thickness 0.15)
				)
				(justify left bottom)
				(hide yes)
			)
		)
		(property "Description" ""
			(at 204.47 240.03 0)
			(effects
				(font
					(size 1.27 1.27)
				)
			)
		)
		(property "Manufacturer" "Panasonic"
			(at 227.33 219.71 0)
			(effects
				(font
					(size 1.27 1.27)
					(thickness 0.15)
				)
				(justify left bottom)
				(hide yes)
			)
		)
		(property "MPN" "ERJ2GE0R00X"
			(at 224.79 219.71 0)
			(effects
				(font
					(size 1.27 1.27)
					(thickness 0.15)
				)
				(justify left bottom)
				(hide yes)
			)
		)
		(property "Val" "0R"
			(at 207.01 238.76 90)
			(effects
				(font
					(size 1.27 1.27)
					(thickness 0.15)
				)
				(justify right)
			)
		)
		(property "DNP" "DNP"
			(at 204.47 235.585 0)
			(effects
				(font
					(size 1.27 1.27)
				)
				(justify right)
			)
		)
		(property "License" "Apache-2.0"
			(at 229.87 219.71 0)
			(effects
				(font
					(size 1.27 1.27)
					(thickness 0.15)
				)
				(justify left bottom)
				(hide yes)
			)
		)
		(property "Author" "Antmicro"
			(at 232.41 219.71 0)
			(effects
				(font
					(size 1.27 1.27)
					(thickness 0.15)
				)
				(justify left bottom)
				(hide yes)
			)
		)
		(property "Tolerance" "~"
			(at 214.63 219.71 0)
			(effects
				(font
					(size 1.27 1.27)
				)
				(justify left bottom)
				(hide yes)
			)
		)
		(property "Current" "1A"
			(at 207.01 241.2999 90)
			(effects
				(font
					(size 1.27 1.27)
					(thickness 0.15)
				)
				(justify right)
				(hide yes)
			)
		)
		(pin "1"
		)
		(pin "2"
		)
		(instances
			(project "k410t-devboard"
				(path ""
					(reference "R307")
					(unit 1)
				)
			)
		)
	)
	(symbol
		(lib_id "antmicroResistors0603:R_0R_22.4A_0603")
		(at 392.43 40.64 0)
		(unit 1)
		(exclude_from_sim no)
		(in_bom yes)
		(on_board yes)
		(dnp no)
		(property "Reference" "R37"
			(at 399.415 39.37 0)
			(effects
				(font
					(size 1.27 1.27)
				)
			)
		)
		(property "Value" "R_0R_22.4A_0603"
			(at 394.97 34.29 0)
			(effects
				(font
					(size 1.27 1.27)
					(thickness 0.15)
				)
				(hide yes)
			)
		)
		(property "Footprint" "antmicro-footprints:R_0603_1608Metric"
			(at 415.29 53.34 0)
			(effects
				(font
					(size 1.27 1.27)
					(thickness 0.15)
				)
				(justify left bottom)
				(hide yes)
			)
		)
		(property "Datasheet" "https://fscdn.rohm.com/en/products/databook/datasheet/passive/resistor/chip_resistor/pmr-jpw-e.pdf"
			(at 415.29 55.88 0)
			(effects
				(font
					(size 1.27 1.27)
					(thickness 0.15)
				)
				(justify left bottom)
				(hide yes)
			)
		)
		(property "Description" ""
			(at 392.43 40.64 0)
			(effects
				(font
					(size 1.27 1.27)
				)
			)
		)
		(property "Manufacturer" "ROHM Semiconductor"
			(at 415.29 58.42 0)
			(effects
				(font
					(size 1.27 1.27)
					(thickness 0.15)
				)
				(justify left bottom)
				(hide yes)
			)
		)
		(property "MPN" "PMR03EZPJ000"
			(at 415.29 60.96 0)
			(effects
				(font
					(size 1.27 1.27)
					(thickness 0.15)
				)
				(justify left bottom)
				(hide yes)
			)
		)
		(property "Val" "0R"
			(at 391.16 39.37 0)
			(effects
				(font
					(size 1.27 1.27)
					(thickness 0.15)
				)
			)
		)
		(property "Author" "Antmicro"
			(at 415.29 63.5 0)
			(effects
				(font
					(size 1.27 1.27)
					(thickness 0.15)
				)
				(justify left bottom)
				(hide yes)
			)
		)
		(property "License" "Apache-2.0"
			(at 415.29 66.04 0)
			(effects
				(font
					(size 1.27 1.27)
					(thickness 0.15)
				)
				(justify left bottom)
				(hide yes)
			)
		)
		(property "Max. Curr." "22.4A"
			(at 392.43 43.18 0)
			(effects
				(font
					(size 1.27 1.27)
					(thickness 0.15)
				)
				(justify left bottom)
			)
		)
		(property "Tolerance" "template_tolerance"
			(at 412.75 50.8 0)
			(effects
				(font
					(size 1.27 1.27)
				)
				(justify left bottom)
				(hide yes)
			)
		)
		(pin "1"
		)
		(pin "2"
		)
		(instances
			(project "k410t-devboard"
				(path ""
					(reference "R37")
					(unit 1)
				)
			)
		)
	)
	(symbol
		(lib_id "antmicropower:GND")
		(at 69.85 238.76 0)
		(unit 1)
		(exclude_from_sim no)
		(in_bom yes)
		(on_board yes)
		(dnp no)
		(fields_autoplaced yes)
		(property "Reference" "#PWR0368"
			(at 69.85 245.11 0)
			(effects
				(font
					(size 1.27 1.27)
				)
				(hide yes)
			)
		)
		(property "Value" "GND"
			(at 69.85 242.57 0)
			(effects
				(font
					(size 1.27 1.27)
				)
			)
		)
		(property "Footprint" ""
			(at 78.74 246.38 0)
			(effects
				(font
					(size 1.27 1.27)
					(thickness 0.15)
				)
				(justify left bottom)
				(hide yes)
			)
		)
		(property "Datasheet" ""
			(at 78.74 251.46 0)
			(effects
				(font
					(size 1.27 1.27)
					(thickness 0.15)
				)
				(justify left bottom)
				(hide yes)
			)
		)
		(property "Description" ""
			(at 69.85 238.76 0)
			(effects
				(font
					(size 1.27 1.27)
				)
			)
		)
		(property "Author" "Antmicro"
			(at 78.74 246.38 0)
			(effects
				(font
					(size 1.27 1.27)
					(thickness 0.15)
				)
				(justify left bottom)
				(hide yes)
			)
		)
		(property "License" "Apache-2.0"
			(at 78.74 248.92 0)
			(effects
				(font
					(size 1.27 1.27)
					(thickness 0.15)
				)
				(justify left bottom)
				(hide yes)
			)
		)
		(pin "1"
		)
		(instances
			(project "k410t-devboard"
				(path ""
					(reference "#PWR0368")
					(unit 1)
				)
			)
		)
	)
	(symbol
		(lib_id "antmicroCapacitors0402:C_1u_0402")
		(at 121.92 266.7 90)
		(unit 1)
		(exclude_from_sim no)
		(in_bom no)
		(on_board yes)
		(dnp yes)
		(property "Reference" "C334"
			(at 122.555 262.255 90)
			(effects
				(font
					(size 1.27 1.27)
				)
				(justify right)
			)
		)
		(property "Value" "C_1u_0402"
			(at 132.08 246.38 0)
			(effects
				(font
					(size 1.27 1.27)
					(thickness 0.15)
				)
				(justify left bottom)
				(hide yes)
			)
		)
		(property "Footprint" "antmicro-footprints:C_0402_1005Metric"
			(at 134.62 246.38 0)
			(effects
				(font
					(size 1.27 1.27)
					(thickness 0.15)
				)
				(justify left bottom)
				(hide yes)
			)
		)
		(property "Datasheet" "https://product.tdk.com/en/search/capacitor/ceramic/mlcc/info?part_no=C1005X6S1A105K050BC"
			(at 137.16 246.38 0)
			(effects
				(font
					(size 1.27 1.27)
					(thickness 0.15)
				)
				(justify left bottom)
				(hide yes)
			)
		)
		(property "Description" ""
			(at 121.92 266.7 0)
			(effects
				(font
					(size 1.27 1.27)
				)
			)
		)
		(property "Manufacturer" "TDK"
			(at 142.24 246.38 0)
			(effects
				(font
					(size 1.27 1.27)
					(thickness 0.15)
				)
				(justify left bottom)
				(hide yes)
			)
		)
		(property "MPN" "C1005X6S1A105K050BC"
			(at 139.7 246.38 0)
			(effects
				(font
					(size 1.27 1.27)
					(thickness 0.15)
				)
				(justify left bottom)
				(hide yes)
			)
		)
		(property "Val" "1u"
			(at 122.555 266.065 90)
			(effects
				(font
					(size 1.27 1.27)
					(thickness 0.15)
				)
				(justify right)
			)
		)
		(property "DNP" "DNP"
			(at 123.825 264.16 90)
			(effects
				(font
					(size 1.27 1.27)
				)
				(justify right)
			)
		)
		(property "License" "Apache-2.0"
			(at 144.78 246.38 0)
			(effects
				(font
					(size 1.27 1.27)
					(thickness 0.15)
				)
				(justify left bottom)
				(hide yes)
			)
		)
		(property "Author" "Antmicro"
			(at 147.32 246.38 0)
			(effects
				(font
					(size 1.27 1.27)
					(thickness 0.15)
				)
				(justify left bottom)
				(hide yes)
			)
		)
		(property "Voltage" ""
			(at 149.86 246.38 0)
			(effects
				(font
					(size 1.27 1.27)
				)
				(justify left bottom)
				(hide yes)
			)
		)
		(property "Dielectric" ""
			(at 152.4 246.38 0)
			(effects
				(font
					(size 1.27 1.27)
				)
				(justify left bottom)
				(hide yes)
			)
		)
		(pin "1"
		)
		(pin "2"
		)
		(instances
			(project "k410t-devboard"
				(path ""
					(reference "C334")
					(unit 1)
				)
			)
		)
	)
	(symbol
		(lib_id "antmicroResistors0603:R_0R_22.4A_0603")
		(at 124.46 133.35 0)
		(unit 1)
		(exclude_from_sim no)
		(in_bom yes)
		(on_board yes)
		(dnp no)
		(property "Reference" "R287"
			(at 127 125.73 0)
			(effects
				(font
					(size 1.27 1.27)
				)
			)
		)
		(property "Value" "R_0R_22.4A_0603"
			(at 127 127 0)
			(effects
				(font
					(size 1.27 1.27)
					(thickness 0.15)
				)
				(hide yes)
			)
		)
		(property "Footprint" "antmicro-footprints:R_0603_1608Metric"
			(at 147.32 146.05 0)
			(effects
				(font
					(size 1.27 1.27)
					(thickness 0.15)
				)
				(justify left bottom)
				(hide yes)
			)
		)
		(property "Datasheet" "https://fscdn.rohm.com/en/products/databook/datasheet/passive/resistor/chip_resistor/pmr-jpw-e.pdf"
			(at 147.32 148.59 0)
			(effects
				(font
					(size 1.27 1.27)
					(thickness 0.15)
				)
				(justify left bottom)
				(hide yes)
			)
		)
		(property "Description" ""
			(at 124.46 133.35 0)
			(effects
				(font
					(size 1.27 1.27)
				)
			)
		)
		(property "Manufacturer" "ROHM Semiconductor"
			(at 147.32 151.13 0)
			(effects
				(font
					(size 1.27 1.27)
					(thickness 0.15)
				)
				(justify left bottom)
				(hide yes)
			)
		)
		(property "MPN" "PMR03EZPJ000"
			(at 147.32 153.67 0)
			(effects
				(font
					(size 1.27 1.27)
					(thickness 0.15)
				)
				(justify left bottom)
				(hide yes)
			)
		)
		(property "Val" "0R"
			(at 127 128.27 0)
			(effects
				(font
					(size 1.27 1.27)
					(thickness 0.15)
				)
			)
		)
		(property "Author" "Antmicro"
			(at 147.32 156.21 0)
			(effects
				(font
					(size 1.27 1.27)
					(thickness 0.15)
				)
				(justify left bottom)
				(hide yes)
			)
		)
		(property "License" "Apache-2.0"
			(at 147.32 158.75 0)
			(effects
				(font
					(size 1.27 1.27)
					(thickness 0.15)
				)
				(justify left bottom)
				(hide yes)
			)
		)
		(property "Max. Curr." "22.4A"
			(at 127 130.81 0)
			(effects
				(font
					(size 1.27 1.27)
					(thickness 0.15)
				)
			)
		)
		(property "Tolerance" "template_tolerance"
			(at 144.78 143.51 0)
			(effects
				(font
					(size 1.27 1.27)
				)
				(justify left bottom)
				(hide yes)
			)
		)
		(pin "1"
		)
		(pin "2"
		)
		(instances
			(project "k410t-devboard"
				(path ""
					(reference "R287")
					(unit 1)
				)
			)
		)
	)
	(symbol
		(lib_id "antmicroCapacitors0603:C_22u_0603")
		(at 119.38 229.87 90)
		(unit 1)
		(exclude_from_sim no)
		(in_bom yes)
		(on_board yes)
		(dnp no)
		(property "Reference" "C332"
			(at 120.015 225.425 90)
			(effects
				(font
					(size 1.27 1.27)
				)
				(justify right)
			)
		)
		(property "Value" "C_22u_0603"
			(at 129.54 209.55 0)
			(effects
				(font
					(size 1.27 1.27)
					(thickness 0.15)
				)
				(justify left bottom)
				(hide yes)
			)
		)
		(property "Footprint" "antmicro-footprints:C_0603_1608Metric"
			(at 132.08 209.55 0)
			(effects
				(font
					(size 1.27 1.27)
					(thickness 0.15)
				)
				(justify left bottom)
				(hide yes)
			)
		)
		(property "Datasheet" "https://www.murata.com/products/productdetail?partno=GRM188R60J226MEA0%23"
			(at 134.62 209.55 0)
			(effects
				(font
					(size 1.27 1.27)
					(thickness 0.15)
				)
				(justify left bottom)
				(hide yes)
			)
		)
		(property "Description" ""
			(at 119.38 229.87 0)
			(effects
				(font
					(size 1.27 1.27)
				)
			)
		)
		(property "Manufacturer" "Murata"
			(at 139.7 209.55 0)
			(effects
				(font
					(size 1.27 1.27)
					(thickness 0.15)
				)
				(justify left bottom)
				(hide yes)
			)
		)
		(property "MPN" "GRM188R60J226MEA0D"
			(at 137.16 209.55 0)
			(effects
				(font
					(size 1.27 1.27)
					(thickness 0.15)
				)
				(justify left bottom)
				(hide yes)
			)
		)
		(property "Val" "22u"
			(at 120.015 229.235 90)
			(effects
				(font
					(size 1.27 1.27)
					(thickness 0.15)
				)
				(justify right)
			)
		)
		(property "License" "Apache-2.0"
			(at 142.24 209.55 0)
			(effects
				(font
					(size 1.27 1.27)
					(thickness 0.15)
				)
				(justify left bottom)
				(hide yes)
			)
		)
		(property "Author" "Antmicro"
			(at 144.78 209.55 0)
			(effects
				(font
					(size 1.27 1.27)
					(thickness 0.15)
				)
				(justify left bottom)
				(hide yes)
			)
		)
		(property "Voltage" ""
			(at 147.32 209.55 0)
			(effects
				(font
					(size 1.27 1.27)
				)
				(justify left bottom)
				(hide yes)
			)
		)
		(property "Dielectric" ""
			(at 149.86 209.55 0)
			(effects
				(font
					(size 1.27 1.27)
				)
				(justify left bottom)
				(hide yes)
			)
		)
		(pin "1"
		)
		(pin "2"
		)
		(instances
			(project "k410t-devboard"
				(path ""
					(reference "C332")
					(unit 1)
				)
			)
		)
	)
	(symbol
		(lib_id "antmicroCapacitors0603:C_22u_0603")
		(at 370.84 53.34 90)
		(unit 1)
		(exclude_from_sim no)
		(in_bom yes)
		(on_board yes)
		(dnp no)
		(property "Reference" "C360"
			(at 371.475 48.895 90)
			(effects
				(font
					(size 1.27 1.27)
				)
				(justify right)
			)
		)
		(property "Value" "C_22u_0603"
			(at 381 33.02 0)
			(effects
				(font
					(size 1.27 1.27)
					(thickness 0.15)
				)
				(justify left bottom)
				(hide yes)
			)
		)
		(property "Footprint" "antmicro-footprints:C_0603_1608Metric"
			(at 383.54 33.02 0)
			(effects
				(font
					(size 1.27 1.27)
					(thickness 0.15)
				)
				(justify left bottom)
				(hide yes)
			)
		)
		(property "Datasheet" "https://www.murata.com/products/productdetail?partno=GRM188R60J226MEA0%23"
			(at 386.08 33.02 0)
			(effects
				(font
					(size 1.27 1.27)
					(thickness 0.15)
				)
				(justify left bottom)
				(hide yes)
			)
		)
		(property "Description" ""
			(at 370.84 53.34 0)
			(effects
				(font
					(size 1.27 1.27)
				)
			)
		)
		(property "Manufacturer" "Murata"
			(at 391.16 33.02 0)
			(effects
				(font
					(size 1.27 1.27)
					(thickness 0.15)
				)
				(justify left bottom)
				(hide yes)
			)
		)
		(property "MPN" "GRM188R60J226MEA0D"
			(at 388.62 33.02 0)
			(effects
				(font
					(size 1.27 1.27)
					(thickness 0.15)
				)
				(justify left bottom)
				(hide yes)
			)
		)
		(property "Val" "22u"
			(at 371.475 52.705 90)
			(effects
				(font
					(size 1.27 1.27)
					(thickness 0.15)
				)
				(justify right)
			)
		)
		(property "License" "Apache-2.0"
			(at 393.7 33.02 0)
			(effects
				(font
					(size 1.27 1.27)
					(thickness 0.15)
				)
				(justify left bottom)
				(hide yes)
			)
		)
		(property "Author" "Antmicro"
			(at 396.24 33.02 0)
			(effects
				(font
					(size 1.27 1.27)
					(thickness 0.15)
				)
				(justify left bottom)
				(hide yes)
			)
		)
		(property "Voltage" ""
			(at 398.78 33.02 0)
			(effects
				(font
					(size 1.27 1.27)
				)
				(justify left bottom)
				(hide yes)
			)
		)
		(property "Dielectric" ""
			(at 401.32 33.02 0)
			(effects
				(font
					(size 1.27 1.27)
				)
				(justify left bottom)
				(hide yes)
			)
		)
		(pin "1"
		)
		(pin "2"
		)
		(instances
			(project "k410t-devboard"
				(path ""
					(reference "C360")
					(unit 1)
				)
			)
		)
	)
	(symbol
		(lib_id "antmicropower:GND")
		(at 281.94 40.64 0)
		(unit 1)
		(exclude_from_sim no)
		(in_bom yes)
		(on_board yes)
		(dnp no)
		(fields_autoplaced yes)
		(property "Reference" "#PWR0412"
			(at 281.94 46.99 0)
			(effects
				(font
					(size 1.27 1.27)
				)
				(hide yes)
			)
		)
		(property "Value" "GND"
			(at 281.94 44.45 0)
			(effects
				(font
					(size 1.27 1.27)
				)
			)
		)
		(property "Footprint" ""
			(at 290.83 48.26 0)
			(effects
				(font
					(size 1.27 1.27)
					(thickness 0.15)
				)
				(justify left bottom)
				(hide yes)
			)
		)
		(property "Datasheet" ""
			(at 290.83 53.34 0)
			(effects
				(font
					(size 1.27 1.27)
					(thickness 0.15)
				)
				(justify left bottom)
				(hide yes)
			)
		)
		(property "Description" ""
			(at 281.94 40.64 0)
			(effects
				(font
					(size 1.27 1.27)
				)
			)
		)
		(property "Author" "Antmicro"
			(at 290.83 48.26 0)
			(effects
				(font
					(size 1.27 1.27)
					(thickness 0.15)
				)
				(justify left bottom)
				(hide yes)
			)
		)
		(property "License" "Apache-2.0"
			(at 290.83 50.8 0)
			(effects
				(font
					(size 1.27 1.27)
					(thickness 0.15)
				)
				(justify left bottom)
				(hide yes)
			)
		)
		(pin "1"
		)
		(instances
			(project "k410t-devboard"
				(path ""
					(reference "#PWR0412")
					(unit 1)
				)
			)
		)
	)
	(symbol
		(lib_id "antmicroPMICPowerDistributionSwitchesLoadDrivers:NCP451AFCT2G")
		(at 129.54 259.08 0)
		(unit 1)
		(exclude_from_sim no)
		(in_bom no)
		(on_board yes)
		(dnp yes)
		(property "Reference" "U34"
			(at 137.16 255.27 0)
			(effects
				(font
					(size 1.27 1.27)
				)
			)
		)
		(property "Value" "NCP451AFCT2G"
			(at 137.16 267.97 0)
			(effects
				(font
					(size 1.27 1.27)
				)
			)
		)
		(property "Footprint" "antmicro-footprints:Onsemi_WLCSP6_1.40x0.90"
			(at 160.02 266.7 0)
			(effects
				(font
					(size 1.27 1.27)
					(thickness 0.15)
				)
				(justify left bottom)
				(hide yes)
			)
		)
		(property "Datasheet" "https://www.mouser.com/datasheet/2/308/NCP451_D-1812749.pdf"
			(at 160.02 269.24 0)
			(effects
				(font
					(size 1.27 1.27)
					(thickness 0.15)
				)
				(justify left bottom)
				(hide yes)
			)
		)
		(property "Description" ""
			(at 129.54 259.08 0)
			(effects
				(font
					(size 1.27 1.27)
				)
			)
		)
		(property "MPN" "NCP451AFCT2G"
			(at 160.02 271.78 0)
			(effects
				(font
					(size 1.27 1.27)
					(thickness 0.15)
				)
				(justify left bottom)
				(hide yes)
			)
		)
		(property "Manufacturer" "ON Semiconductor"
			(at 160.02 274.32 0)
			(effects
				(font
					(size 1.27 1.27)
					(thickness 0.15)
				)
				(justify left bottom)
				(hide yes)
			)
		)
		(property "DNP" "DNP"
			(at 137.16 261.62 0)
			(effects
				(font
					(size 1.27 1.27)
				)
			)
		)
		(property "Author" "Antmicro"
			(at 160.02 276.86 0)
			(effects
				(font
					(size 1.27 1.27)
					(thickness 0.15)
				)
				(justify left bottom)
				(hide yes)
			)
		)
		(property "License" "Apache-2.0"
			(at 160.02 279.4 0)
			(effects
				(font
					(size 1.27 1.27)
					(thickness 0.15)
				)
				(justify left bottom)
				(hide yes)
			)
		)
		(pin "A1"
		)
		(pin "A2"
		)
		(pin "B1"
		)
		(pin "B2"
		)
		(pin "C1"
		)
		(pin "C2"
		)
		(instances
			(project "k410t-devboard"
				(path ""
					(reference "U34")
					(unit 1)
				)
			)
		)
	)
	(symbol
		(lib_id "antmicroCapacitors0603:C_22u_0603")
		(at 119.38 101.6 90)
		(unit 1)
		(exclude_from_sim no)
		(in_bom yes)
		(on_board yes)
		(dnp no)
		(property "Reference" "C326"
			(at 120.015 97.155 90)
			(effects
				(font
					(size 1.27 1.27)
				)
				(justify right)
			)
		)
		(property "Value" "C_22u_0603"
			(at 129.54 81.28 0)
			(effects
				(font
					(size 1.27 1.27)
					(thickness 0.15)
				)
				(justify left bottom)
				(hide yes)
			)
		)
		(property "Footprint" "antmicro-footprints:C_0603_1608Metric"
			(at 132.08 81.28 0)
			(effects
				(font
					(size 1.27 1.27)
					(thickness 0.15)
				)
				(justify left bottom)
				(hide yes)
			)
		)
		(property "Datasheet" "https://www.murata.com/products/productdetail?partno=GRM188R60J226MEA0%23"
			(at 134.62 81.28 0)
			(effects
				(font
					(size 1.27 1.27)
					(thickness 0.15)
				)
				(justify left bottom)
				(hide yes)
			)
		)
		(property "Description" ""
			(at 119.38 101.6 0)
			(effects
				(font
					(size 1.27 1.27)
				)
			)
		)
		(property "Manufacturer" "Murata"
			(at 139.7 81.28 0)
			(effects
				(font
					(size 1.27 1.27)
					(thickness 0.15)
				)
				(justify left bottom)
				(hide yes)
			)
		)
		(property "MPN" "GRM188R60J226MEA0D"
			(at 137.16 81.28 0)
			(effects
				(font
					(size 1.27 1.27)
					(thickness 0.15)
				)
				(justify left bottom)
				(hide yes)
			)
		)
		(property "Val" "22u"
			(at 120.015 100.965 90)
			(effects
				(font
					(size 1.27 1.27)
					(thickness 0.15)
				)
				(justify right)
			)
		)
		(property "License" "Apache-2.0"
			(at 142.24 81.28 0)
			(effects
				(font
					(size 1.27 1.27)
					(thickness 0.15)
				)
				(justify left bottom)
				(hide yes)
			)
		)
		(property "Author" "Antmicro"
			(at 144.78 81.28 0)
			(effects
				(font
					(size 1.27 1.27)
					(thickness 0.15)
				)
				(justify left bottom)
				(hide yes)
			)
		)
		(property "Voltage" ""
			(at 147.32 81.28 0)
			(effects
				(font
					(size 1.27 1.27)
				)
				(justify left bottom)
				(hide yes)
			)
		)
		(property "Dielectric" ""
			(at 149.86 81.28 0)
			(effects
				(font
					(size 1.27 1.27)
				)
				(justify left bottom)
				(hide yes)
			)
		)
		(pin "1"
		)
		(pin "2"
		)
		(instances
			(project "k410t-devboard"
				(path ""
					(reference "C326")
					(unit 1)
				)
			)
		)
	)
	(symbol
		(lib_id "antmicropower:GND")
		(at 187.96 165.1 0)
		(unit 1)
		(exclude_from_sim no)
		(in_bom yes)
		(on_board yes)
		(dnp no)
		(property "Reference" "#PWR0396"
			(at 187.96 171.45 0)
			(effects
				(font
					(size 1.27 1.27)
				)
				(hide yes)
			)
		)
		(property "Value" "GND"
			(at 187.96 168.91 0)
			(effects
				(font
					(size 1.27 1.27)
				)
			)
		)
		(property "Footprint" ""
			(at 196.85 172.72 0)
			(effects
				(font
					(size 1.27 1.27)
					(thickness 0.15)
				)
				(justify left bottom)
				(hide yes)
			)
		)
		(property "Datasheet" ""
			(at 196.85 177.8 0)
			(effects
				(font
					(size 1.27 1.27)
					(thickness 0.15)
				)
				(justify left bottom)
				(hide yes)
			)
		)
		(property "Description" ""
			(at 187.96 165.1 0)
			(effects
				(font
					(size 1.27 1.27)
				)
			)
		)
		(property "Author" "Antmicro"
			(at 196.85 172.72 0)
			(effects
				(font
					(size 1.27 1.27)
					(thickness 0.15)
				)
				(justify left bottom)
				(hide yes)
			)
		)
		(property "License" "Apache-2.0"
			(at 196.85 175.26 0)
			(effects
				(font
					(size 1.27 1.27)
					(thickness 0.15)
				)
				(justify left bottom)
				(hide yes)
			)
		)
		(pin "1"
		)
		(instances
			(project "k410t-devboard"
				(path ""
					(reference "#PWR0396")
					(unit 1)
				)
			)
		)
	)
	(symbol
		(lib_id "antmicroResistors0402:R_47k_0402")
		(at 119.38 33.02 270)
		(mirror x)
		(unit 1)
		(exclude_from_sim no)
		(in_bom yes)
		(on_board yes)
		(dnp no)
		(property "Reference" "R367"
			(at 118.11 29.21 90)
			(effects
				(font
					(size 1.27 1.27)
				)
				(justify right)
			)
		)
		(property "Value" "R_47k_0402"
			(at 106.68 12.7 0)
			(effects
				(font
					(size 1.27 1.27)
					(thickness 0.15)
				)
				(justify left bottom)
				(hide yes)
			)
		)
		(property "Footprint" "antmicro-footprints:R_0402_1005Metric"
			(at 104.14 12.7 0)
			(effects
				(font
					(size 1.27 1.27)
					(thickness 0.15)
				)
				(justify left bottom)
				(hide yes)
			)
		)
		(property "Datasheet" "https://www.bourns.com/docs/product-datasheets/cr.pdf"
			(at 101.6 12.7 0)
			(effects
				(font
					(size 1.27 1.27)
					(thickness 0.15)
				)
				(justify left bottom)
				(hide yes)
			)
		)
		(property "Description" ""
			(at 119.38 33.02 0)
			(effects
				(font
					(size 1.27 1.27)
				)
			)
		)
		(property "Manufacturer" "Bourns"
			(at 96.52 12.7 0)
			(effects
				(font
					(size 1.27 1.27)
					(thickness 0.15)
				)
				(justify left bottom)
				(hide yes)
			)
		)
		(property "MPN" "CR0402-FX-4702GLF"
			(at 99.06 12.7 0)
			(effects
				(font
					(size 1.27 1.27)
					(thickness 0.15)
				)
				(justify left bottom)
				(hide yes)
			)
		)
		(property "Val" "47k"
			(at 118.11 31.75 90)
			(effects
				(font
					(size 1.27 1.27)
					(thickness 0.15)
				)
				(justify right)
			)
		)
		(property "License" "Apache-2.0"
			(at 93.98 12.7 0)
			(effects
				(font
					(size 1.27 1.27)
					(thickness 0.15)
				)
				(justify left bottom)
				(hide yes)
			)
		)
		(property "Author" "Antmicro"
			(at 91.44 12.7 0)
			(effects
				(font
					(size 1.27 1.27)
					(thickness 0.15)
				)
				(justify left bottom)
				(hide yes)
			)
		)
		(property "Tolerance" "1%"
			(at 109.22 12.7 0)
			(effects
				(font
					(size 1.27 1.27)
				)
				(justify left bottom)
				(hide yes)
			)
		)
		(pin "1"
		)
		(pin "2"
		)
		(instances
			(project "k410t-devboard"
				(path ""
					(reference "R367")
					(unit 1)
				)
			)
		)
	)
	(symbol
		(lib_id "k410t-devboard:Net-Tie_2")
		(at 256.54 224.79 90)
		(unit 1)
		(exclude_from_sim no)
		(in_bom yes)
		(on_board yes)
		(dnp no)
		(fields_autoplaced yes)
		(property "Reference" "NT28"
			(at 255.27 224.79 0)
			(effects
				(font
					(size 1.27 1.27)
				)
				(hide yes)
			)
		)
		(property "Value" "Net-Tie_2"
			(at 258.445 222.8849 90)
			(effects
				(font
					(size 1.27 1.27)
					(thickness 0.15)
				)
				(justify right)
				(hide yes)
			)
		)
		(property "Footprint" "antmicro-footprints:NetTie-2_SMD_Pad0.127mm"
			(at 261.62 203.2 0)
			(effects
				(font
					(size 1.27 1.27)
					(thickness 0.15)
				)
				(justify left bottom)
				(hide yes)
			)
		)
		(property "Datasheet" ""
			(at 264.16 203.2 0)
			(effects
				(font
					(size 1.27 1.27)
					(thickness 0.15)
				)
				(justify left bottom)
				(hide yes)
			)
		)
		(property "Description" ""
			(at 256.54 224.79 0)
			(effects
				(font
					(size 1.27 1.27)
				)
			)
		)
		(property "MPN" ""
			(at 265.43 203.2 0)
			(effects
				(font
					(size 1.27 1.27)
				)
				(justify left)
				(hide yes)
			)
		)
		(property "Manufacturer" ""
			(at 267.97 203.2 0)
			(effects
				(font
					(size 1.27 1.27)
				)
				(justify left)
				(hide yes)
			)
		)
		(property "Author" "Antmicro"
			(at 271.78 203.2 0)
			(effects
				(font
					(size 1.27 1.27)
					(thickness 0.15)
				)
				(justify left bottom)
				(hide yes)
			)
		)
		(property "License" "Apache-2.0"
			(at 274.32 203.2 0)
			(effects
				(font
					(size 1.27 1.27)
					(thickness 0.15)
				)
				(justify left bottom)
				(hide yes)
			)
		)
		(pin "1"
		)
		(pin "2"
		)
		(instances
			(project "k410t-devboard"
				(path ""
					(reference "NT28")
					(unit 1)
				)
			)
		)
	)
	(symbol
		(lib_id "antmicroResistors0402:R_47k_0402")
		(at 147.32 38.1 0)
		(mirror x)
		(unit 1)
		(exclude_from_sim no)
		(in_bom yes)
		(on_board yes)
		(dnp no)
		(property "Reference" "R293"
			(at 149.86 40.64 0)
			(effects
				(font
					(size 1.27 1.27)
				)
			)
		)
		(property "Value" "R_47k_0402"
			(at 167.64 25.4 0)
			(effects
				(font
					(size 1.27 1.27)
					(thickness 0.15)
				)
				(justify left bottom)
				(hide yes)
			)
		)
		(property "Footprint" "antmicro-footprints:R_0402_1005Metric"
			(at 167.64 22.86 0)
			(effects
				(font
					(size 1.27 1.27)
					(thickness 0.15)
				)
				(justify left bottom)
				(hide yes)
			)
		)
		(property "Datasheet" "https://www.bourns.com/docs/product-datasheets/cr.pdf"
			(at 167.64 20.32 0)
			(effects
				(font
					(size 1.27 1.27)
					(thickness 0.15)
				)
				(justify left bottom)
				(hide yes)
			)
		)
		(property "Description" ""
			(at 147.32 38.1 0)
			(effects
				(font
					(size 1.27 1.27)
				)
			)
		)
		(property "Manufacturer" "Bourns"
			(at 167.64 15.24 0)
			(effects
				(font
					(size 1.27 1.27)
					(thickness 0.15)
				)
				(justify left bottom)
				(hide yes)
			)
		)
		(property "MPN" "CR0402-FX-4702GLF"
			(at 167.64 17.78 0)
			(effects
				(font
					(size 1.27 1.27)
					(thickness 0.15)
				)
				(justify left bottom)
				(hide yes)
			)
		)
		(property "Val" "47k"
			(at 149.86 43.18 0)
			(effects
				(font
					(size 1.27 1.27)
					(thickness 0.15)
				)
			)
		)
		(property "License" "Apache-2.0"
			(at 167.64 12.7 0)
			(effects
				(font
					(size 1.27 1.27)
					(thickness 0.15)
				)
				(justify left bottom)
				(hide yes)
			)
		)
		(property "Author" "Antmicro"
			(at 167.64 10.16 0)
			(effects
				(font
					(size 1.27 1.27)
					(thickness 0.15)
				)
				(justify left bottom)
				(hide yes)
			)
		)
		(property "Tolerance" "1%"
			(at 167.64 27.94 0)
			(effects
				(font
					(size 1.27 1.27)
				)
				(justify left bottom)
				(hide yes)
			)
		)
		(pin "1"
		)
		(pin "2"
		)
		(instances
			(project "k410t-devboard"
				(path ""
					(reference "R293")
					(unit 1)
				)
			)
		)
	)
	(symbol
		(lib_id "antmicroCapacitors0402:C_100n_0402")
		(at 401.32 214.63 90)
		(unit 1)
		(exclude_from_sim no)
		(in_bom yes)
		(on_board yes)
		(dnp no)
		(property "Reference" "C400"
			(at 401.955 210.185 90)
			(effects
				(font
					(size 1.27 1.27)
				)
				(justify right)
			)
		)
		(property "Value" "C_100n_0402"
			(at 411.48 194.31 0)
			(effects
				(font
					(size 1.27 1.27)
					(thickness 0.15)
				)
				(justify left bottom)
				(hide yes)
			)
		)
		(property "Footprint" "antmicro-footprints:C_0402_1005Metric"
			(at 414.02 194.31 0)
			(effects
				(font
					(size 1.27 1.27)
					(thickness 0.15)
				)
				(justify left bottom)
				(hide yes)
			)
		)
		(property "Datasheet" "https://www.murata.com/products/productdetail?partno=GRM155R61H104KE14%23"
			(at 416.56 194.31 0)
			(effects
				(font
					(size 1.27 1.27)
					(thickness 0.15)
				)
				(justify left bottom)
				(hide yes)
			)
		)
		(property "Description" ""
			(at 401.32 214.63 0)
			(effects
				(font
					(size 1.27 1.27)
				)
			)
		)
		(property "Manufacturer" "Murata"
			(at 421.64 194.31 0)
			(effects
				(font
					(size 1.27 1.27)
					(thickness 0.15)
				)
				(justify left bottom)
				(hide yes)
			)
		)
		(property "MPN" "GRM155R61H104KE14D"
			(at 419.1 194.31 0)
			(effects
				(font
					(size 1.27 1.27)
					(thickness 0.15)
				)
				(justify left bottom)
				(hide yes)
			)
		)
		(property "Val" "100n"
			(at 401.955 213.995 90)
			(effects
				(font
					(size 1.27 1.27)
					(thickness 0.15)
				)
				(justify right)
			)
		)
		(property "License" "Apache-2.0"
			(at 424.18 194.31 0)
			(effects
				(font
					(size 1.27 1.27)
					(thickness 0.15)
				)
				(justify left bottom)
				(hide yes)
			)
		)
		(property "Author" "Antmicro"
			(at 426.72 194.31 0)
			(effects
				(font
					(size 1.27 1.27)
					(thickness 0.15)
				)
				(justify left bottom)
				(hide yes)
			)
		)
		(property "Voltage" "50V"
			(at 429.26 194.31 0)
			(effects
				(font
					(size 1.27 1.27)
				)
				(justify left bottom)
				(hide yes)
			)
		)
		(property "Dielectric" "X5R"
			(at 431.8 194.31 0)
			(effects
				(font
					(size 1.27 1.27)
				)
				(justify left bottom)
				(hide yes)
			)
		)
		(pin "1"
		)
		(pin "2"
		)
		(instances
			(project "k410t-devboard"
				(path ""
					(reference "C400")
					(unit 1)
				)
			)
		)
	)
	(symbol
		(lib_id "antmicropower:+3V3_AON")
		(at 55.88 38.1 0)
		(unit 1)
		(exclude_from_sim no)
		(in_bom yes)
		(on_board yes)
		(dnp no)
		(property "Reference" "#PWR0472"
			(at 55.88 41.91 0)
			(effects
				(font
					(size 1.27 1.27)
				)
				(hide yes)
			)
		)
		(property "Value" "+3V3_AON"
			(at 55.88 34.29 0)
			(effects
				(font
					(size 1.27 1.27)
				)
			)
		)
		(property "Footprint" ""
			(at 55.88 38.1 0)
			(effects
				(font
					(size 1.27 1.27)
				)
				(hide yes)
			)
		)
		(property "Datasheet" ""
			(at 55.88 38.1 0)
			(effects
				(font
					(size 1.27 1.27)
				)
				(hide yes)
			)
		)
		(property "Description" ""
			(at 55.88 38.1 0)
			(effects
				(font
					(size 1.27 1.27)
				)
			)
		)
		(pin "1"
		)
		(instances
			(project "k410t-devboard"
				(path ""
					(reference "#PWR0472")
					(unit 1)
				)
			)
		)
	)
	(symbol
		(lib_id "antmicroResistors0402:R_0R_0402")
		(at 212.09 273.05 90)
		(unit 1)
		(exclude_from_sim no)
		(in_bom no)
		(on_board yes)
		(dnp yes)
		(property "Reference" "R363"
			(at 214.63 269.24 90)
			(effects
				(font
					(size 1.27 1.27)
				)
				(justify right)
			)
		)
		(property "Value" "R_0R_0402"
			(at 224.79 252.73 0)
			(effects
				(font
					(size 1.27 1.27)
					(thickness 0.15)
				)
				(justify left bottom)
				(hide yes)
			)
		)
		(property "Footprint" "antmicro-footprints:R_0402_1005Metric"
			(at 227.33 252.73 0)
			(effects
				(font
					(size 1.27 1.27)
					(thickness 0.15)
				)
				(justify left bottom)
				(hide yes)
			)
		)
		(property "Datasheet" "https://industrial.panasonic.com/cdbs/www-data/pdf/RDA0000/AOA0000C301.pdf"
			(at 229.87 252.73 0)
			(effects
				(font
					(size 1.27 1.27)
					(thickness 0.15)
				)
				(justify left bottom)
				(hide yes)
			)
		)
		(property "Description" ""
			(at 212.09 273.05 0)
			(effects
				(font
					(size 1.27 1.27)
				)
			)
		)
		(property "Manufacturer" "Panasonic"
			(at 234.95 252.73 0)
			(effects
				(font
					(size 1.27 1.27)
					(thickness 0.15)
				)
				(justify left bottom)
				(hide yes)
			)
		)
		(property "MPN" "ERJ2GE0R00X"
			(at 232.41 252.73 0)
			(effects
				(font
					(size 1.27 1.27)
					(thickness 0.15)
				)
				(justify left bottom)
				(hide yes)
			)
		)
		(property "Val" "0R"
			(at 214.63 271.78 90)
			(effects
				(font
					(size 1.27 1.27)
					(thickness 0.15)
				)
				(justify right)
			)
		)
		(property "DNP" "DNP"
			(at 212.09 268.605 0)
			(effects
				(font
					(size 1.27 1.27)
				)
				(justify right)
			)
		)
		(property "License" "Apache-2.0"
			(at 237.49 252.73 0)
			(effects
				(font
					(size 1.27 1.27)
					(thickness 0.15)
				)
				(justify left bottom)
				(hide yes)
			)
		)
		(property "Author" "Antmicro"
			(at 240.03 252.73 0)
			(effects
				(font
					(size 1.27 1.27)
					(thickness 0.15)
				)
				(justify left bottom)
				(hide yes)
			)
		)
		(property "Tolerance" "~"
			(at 222.25 252.73 0)
			(effects
				(font
					(size 1.27 1.27)
				)
				(justify left bottom)
				(hide yes)
			)
		)
		(property "Current" "1A"
			(at 214.63 274.3199 90)
			(effects
				(font
					(size 1.27 1.27)
					(thickness 0.15)
				)
				(justify right)
				(hide yes)
			)
		)
		(pin "1"
		)
		(pin "2"
		)
		(instances
			(project "k410t-devboard"
				(path ""
					(reference "R363")
					(unit 1)
				)
			)
		)
	)
	(symbol
		(lib_id "antmicropower:+3.3V")
		(at 383.54 228.6 0)
		(unit 1)
		(exclude_from_sim no)
		(in_bom yes)
		(on_board yes)
		(dnp no)
		(fields_autoplaced yes)
		(property "Reference" "#PWR0500"
			(at 383.54 232.41 0)
			(effects
				(font
					(size 1.27 1.27)
				)
				(hide yes)
			)
		)
		(property "Value" "+3V3"
			(at 383.54 225.044 0)
			(effects
				(font
					(size 1.27 1.27)
				)
			)
		)
		(property "Footprint" ""
			(at 383.54 228.6 0)
			(effects
				(font
					(size 1.27 1.27)
				)
				(hide yes)
			)
		)
		(property "Datasheet" ""
			(at 383.54 228.6 0)
			(effects
				(font
					(size 1.27 1.27)
				)
				(hide yes)
			)
		)
		(property "Description" ""
			(at 383.54 228.6 0)
			(effects
				(font
					(size 1.27 1.27)
				)
			)
		)
		(pin "1"
		)
		(instances
			(project "k410t-devboard"
				(path ""
					(reference "#PWR0500")
					(unit 1)
				)
			)
		)
	)
	(symbol
		(lib_id "antmicroCapacitors0603:C_22u_0603")
		(at 119.38 190.5 90)
		(unit 1)
		(exclude_from_sim no)
		(in_bom yes)
		(on_board yes)
		(dnp no)
		(property "Reference" "C330"
			(at 120.015 186.055 90)
			(effects
				(font
					(size 1.27 1.27)
				)
				(justify right)
			)
		)
		(property "Value" "C_22u_0603"
			(at 129.54 170.18 0)
			(effects
				(font
					(size 1.27 1.27)
					(thickness 0.15)
				)
				(justify left bottom)
				(hide yes)
			)
		)
		(property "Footprint" "antmicro-footprints:C_0603_1608Metric"
			(at 132.08 170.18 0)
			(effects
				(font
					(size 1.27 1.27)
					(thickness 0.15)
				)
				(justify left bottom)
				(hide yes)
			)
		)
		(property "Datasheet" "https://www.murata.com/products/productdetail?partno=GRM188R60J226MEA0%23"
			(at 134.62 170.18 0)
			(effects
				(font
					(size 1.27 1.27)
					(thickness 0.15)
				)
				(justify left bottom)
				(hide yes)
			)
		)
		(property "Description" ""
			(at 119.38 190.5 0)
			(effects
				(font
					(size 1.27 1.27)
				)
			)
		)
		(property "Manufacturer" "Murata"
			(at 139.7 170.18 0)
			(effects
				(font
					(size 1.27 1.27)
					(thickness 0.15)
				)
				(justify left bottom)
				(hide yes)
			)
		)
		(property "MPN" "GRM188R60J226MEA0D"
			(at 137.16 170.18 0)
			(effects
				(font
					(size 1.27 1.27)
					(thickness 0.15)
				)
				(justify left bottom)
				(hide yes)
			)
		)
		(property "Val" "22u"
			(at 120.015 189.865 90)
			(effects
				(font
					(size 1.27 1.27)
					(thickness 0.15)
				)
				(justify right)
			)
		)
		(property "License" "Apache-2.0"
			(at 142.24 170.18 0)
			(effects
				(font
					(size 1.27 1.27)
					(thickness 0.15)
				)
				(justify left bottom)
				(hide yes)
			)
		)
		(property "Author" "Antmicro"
			(at 144.78 170.18 0)
			(effects
				(font
					(size 1.27 1.27)
					(thickness 0.15)
				)
				(justify left bottom)
				(hide yes)
			)
		)
		(property "Voltage" ""
			(at 147.32 170.18 0)
			(effects
				(font
					(size 1.27 1.27)
				)
				(justify left bottom)
				(hide yes)
			)
		)
		(property "Dielectric" ""
			(at 149.86 170.18 0)
			(effects
				(font
					(size 1.27 1.27)
				)
				(justify left bottom)
				(hide yes)
			)
		)
		(pin "1"
		)
		(pin "2"
		)
		(instances
			(project "k410t-devboard"
				(path ""
					(reference "C330")
					(unit 1)
				)
			)
		)
	)
	(symbol
		(lib_id "antmicropower:+5V")
		(at 133.35 220.98 0)
		(unit 1)
		(exclude_from_sim no)
		(in_bom yes)
		(on_board yes)
		(dnp no)
		(fields_autoplaced yes)
		(property "Reference" "#PWR0354"
			(at 133.35 224.79 0)
			(effects
				(font
					(size 1.27 1.27)
				)
				(hide yes)
			)
		)
		(property "Value" "+5V"
			(at 133.35 217.424 0)
			(effects
				(font
					(size 1.27 1.27)
				)
			)
		)
		(property "Footprint" ""
			(at 133.35 220.98 0)
			(effects
				(font
					(size 1.27 1.27)
				)
				(hide yes)
			)
		)
		(property "Datasheet" ""
			(at 133.35 220.98 0)
			(effects
				(font
					(size 1.27 1.27)
				)
				(hide yes)
			)
		)
		(property "Description" ""
			(at 133.35 220.98 0)
			(effects
				(font
					(size 1.27 1.27)
				)
			)
		)
		(property "Author" "Antmicro"
			(at 148.59 228.6 0)
			(effects
				(font
					(size 1.27 1.27)
					(thickness 0.15)
				)
				(justify left bottom)
				(hide yes)
			)
		)
		(property "License" "Apache-2.0"
			(at 148.59 231.14 0)
			(effects
				(font
					(size 1.27 1.27)
					(thickness 0.15)
				)
				(justify left bottom)
				(hide yes)
			)
		)
		(pin "1"
		)
		(instances
			(project "k410t-devboard"
				(path ""
					(reference "#PWR0354")
					(unit 1)
				)
			)
		)
	)
	(symbol
		(lib_id "antmicroPMICPowerDistributionSwitchesLoadDrivers:REF3012AIDBZT")
		(at 355.6 161.29 0)
		(unit 1)
		(exclude_from_sim no)
		(in_bom yes)
		(on_board yes)
		(dnp no)
		(fields_autoplaced yes)
		(property "Reference" "U41"
			(at 364.49 154.94 0)
			(effects
				(font
					(size 1.27 1.27)
				)
			)
		)
		(property "Value" "REF3012AIDBZT"
			(at 364.49 157.48 0)
			(effects
				(font
					(size 1.27 1.27)
					(thickness 0.15)
				)
				(hide yes)
			)
		)
		(property "Footprint" "antmicro-footprints:SOT-23-3"
			(at 388.62 171.45 0)
			(effects
				(font
					(size 1.27 1.27)
					(thickness 0.15)
				)
				(justify left bottom)
				(hide yes)
			)
		)
		(property "Datasheet" "https://www.ti.com/lit/gpn/REF3012"
			(at 388.62 173.99 0)
			(effects
				(font
					(size 1.27 1.27)
					(thickness 0.15)
				)
				(justify left bottom)
				(hide yes)
			)
		)
		(property "Description" ""
			(at 355.6 161.29 0)
			(effects
				(font
					(size 1.27 1.27)
				)
			)
		)
		(property "MPN" "REF3012AIDBZT"
			(at 364.49 157.48 0)
			(effects
				(font
					(size 1.27 1.27)
					(thickness 0.15)
				)
			)
		)
		(property "Manufacturer" "Texas Instruments"
			(at 388.62 179.07 0)
			(effects
				(font
					(size 1.27 1.27)
					(thickness 0.15)
				)
				(justify left bottom)
				(hide yes)
			)
		)
		(property "Author" "Antmicro"
			(at 388.62 181.61 0)
			(effects
				(font
					(size 1.27 1.27)
					(thickness 0.15)
				)
				(justify left bottom)
				(hide yes)
			)
		)
		(property "License" "Apache-2.0"
			(at 388.62 184.15 0)
			(effects
				(font
					(size 1.27 1.27)
					(thickness 0.15)
				)
				(justify left bottom)
				(hide yes)
			)
		)
		(pin "1"
		)
		(pin "2"
		)
		(pin "3"
		)
		(instances
			(project "k410t-devboard"
				(path ""
					(reference "U41")
					(unit 1)
				)
			)
		)
	)
	(symbol
		(lib_id "antmicroResistors0603:R_0R_22.4A_0603")
		(at 392.43 45.72 0)
		(unit 1)
		(exclude_from_sim no)
		(in_bom yes)
		(on_board yes)
		(dnp no)
		(property "Reference" "R333"
			(at 400.05 44.45 0)
			(effects
				(font
					(size 1.27 1.27)
				)
			)
		)
		(property "Value" "R_0R_22.4A_0603"
			(at 394.97 40.005 0)
			(effects
				(font
					(size 1.27 1.27)
					(thickness 0.15)
				)
				(hide yes)
			)
		)
		(property "Footprint" "antmicro-footprints:R_0603_1608Metric"
			(at 415.29 58.42 0)
			(effects
				(font
					(size 1.27 1.27)
					(thickness 0.15)
				)
				(justify left bottom)
				(hide yes)
			)
		)
		(property "Datasheet" "https://fscdn.rohm.com/en/products/databook/datasheet/passive/resistor/chip_resistor/pmr-jpw-e.pdf"
			(at 415.29 60.96 0)
			(effects
				(font
					(size 1.27 1.27)
					(thickness 0.15)
				)
				(justify left bottom)
				(hide yes)
			)
		)
		(property "Description" ""
			(at 392.43 45.72 0)
			(effects
				(font
					(size 1.27 1.27)
				)
			)
		)
		(property "Manufacturer" "ROHM Semiconductor"
			(at 415.29 63.5 0)
			(effects
				(font
					(size 1.27 1.27)
					(thickness 0.15)
				)
				(justify left bottom)
				(hide yes)
			)
		)
		(property "MPN" "PMR03EZPJ000"
			(at 415.29 66.04 0)
			(effects
				(font
					(size 1.27 1.27)
					(thickness 0.15)
				)
				(justify left bottom)
				(hide yes)
			)
		)
		(property "Val" "0R"
			(at 391.16 44.45 0)
			(effects
				(font
					(size 1.27 1.27)
					(thickness 0.15)
				)
			)
		)
		(property "Author" "Antmicro"
			(at 415.29 68.58 0)
			(effects
				(font
					(size 1.27 1.27)
					(thickness 0.15)
				)
				(justify left bottom)
				(hide yes)
			)
		)
		(property "License" "Apache-2.0"
			(at 415.29 71.12 0)
			(effects
				(font
					(size 1.27 1.27)
					(thickness 0.15)
				)
				(justify left bottom)
				(hide yes)
			)
		)
		(property "Max. Curr." "22.4A"
			(at 392.43 48.26 0)
			(effects
				(font
					(size 1.27 1.27)
					(thickness 0.15)
				)
				(justify left bottom)
			)
		)
		(property "Tolerance" "template_tolerance"
			(at 412.75 55.88 0)
			(effects
				(font
					(size 1.27 1.27)
				)
				(justify left bottom)
				(hide yes)
			)
		)
		(pin "1"
		)
		(pin "2"
		)
		(instances
			(project "k410t-devboard"
				(path ""
					(reference "R333")
					(unit 1)
				)
			)
		)
	)
	(symbol
		(lib_id "antmicropower:GND")
		(at 350.52 78.74 0)
		(unit 1)
		(exclude_from_sim no)
		(in_bom yes)
		(on_board yes)
		(dnp no)
		(fields_autoplaced yes)
		(property "Reference" "#PWR0433"
			(at 350.52 85.09 0)
			(effects
				(font
					(size 1.27 1.27)
				)
				(hide yes)
			)
		)
		(property "Value" "GND"
			(at 350.52 82.55 0)
			(effects
				(font
					(size 1.27 1.27)
				)
			)
		)
		(property "Footprint" ""
			(at 359.41 86.36 0)
			(effects
				(font
					(size 1.27 1.27)
					(thickness 0.15)
				)
				(justify left bottom)
				(hide yes)
			)
		)
		(property "Datasheet" ""
			(at 359.41 91.44 0)
			(effects
				(font
					(size 1.27 1.27)
					(thickness 0.15)
				)
				(justify left bottom)
				(hide yes)
			)
		)
		(property "Description" ""
			(at 350.52 78.74 0)
			(effects
				(font
					(size 1.27 1.27)
				)
			)
		)
		(property "Author" "Antmicro"
			(at 359.41 86.36 0)
			(effects
				(font
					(size 1.27 1.27)
					(thickness 0.15)
				)
				(justify left bottom)
				(hide yes)
			)
		)
		(property "License" "Apache-2.0"
			(at 359.41 88.9 0)
			(effects
				(font
					(size 1.27 1.27)
					(thickness 0.15)
				)
				(justify left bottom)
				(hide yes)
			)
		)
		(pin "1"
		)
		(instances
			(project "k410t-devboard"
				(path ""
					(reference "#PWR0433")
					(unit 1)
				)
			)
		)
	)
	(symbol
		(lib_id "antmicroResistors0402:R_0R_0402")
		(at 238.76 113.03 90)
		(unit 1)
		(exclude_from_sim no)
		(in_bom no)
		(on_board yes)
		(dnp yes)
		(property "Reference" "R310"
			(at 241.3 109.22 90)
			(effects
				(font
					(size 1.27 1.27)
				)
				(justify right)
			)
		)
		(property "Value" "R_0R_0402"
			(at 251.46 92.71 0)
			(effects
				(font
					(size 1.27 1.27)
					(thickness 0.15)
				)
				(justify left bottom)
				(hide yes)
			)
		)
		(property "Footprint" "antmicro-footprints:R_0402_1005Metric"
			(at 254 92.71 0)
			(effects
				(font
					(size 1.27 1.27)
					(thickness 0.15)
				)
				(justify left bottom)
				(hide yes)
			)
		)
		(property "Datasheet" "https://industrial.panasonic.com/cdbs/www-data/pdf/RDA0000/AOA0000C301.pdf"
			(at 256.54 92.71 0)
			(effects
				(font
					(size 1.27 1.27)
					(thickness 0.15)
				)
				(justify left bottom)
				(hide yes)
			)
		)
		(property "Description" ""
			(at 238.76 113.03 0)
			(effects
				(font
					(size 1.27 1.27)
				)
			)
		)
		(property "Manufacturer" "Panasonic"
			(at 261.62 92.71 0)
			(effects
				(font
					(size 1.27 1.27)
					(thickness 0.15)
				)
				(justify left bottom)
				(hide yes)
			)
		)
		(property "MPN" "ERJ2GE0R00X"
			(at 259.08 92.71 0)
			(effects
				(font
					(size 1.27 1.27)
					(thickness 0.15)
				)
				(justify left bottom)
				(hide yes)
			)
		)
		(property "Val" "0R"
			(at 241.3 111.76 90)
			(effects
				(font
					(size 1.27 1.27)
					(thickness 0.15)
				)
				(justify right)
			)
		)
		(property "DNP" "DNP"
			(at 238.76 108.585 0)
			(effects
				(font
					(size 1.27 1.27)
				)
				(justify right)
			)
		)
		(property "License" "Apache-2.0"
			(at 264.16 92.71 0)
			(effects
				(font
					(size 1.27 1.27)
					(thickness 0.15)
				)
				(justify left bottom)
				(hide yes)
			)
		)
		(property "Author" "Antmicro"
			(at 266.7 92.71 0)
			(effects
				(font
					(size 1.27 1.27)
					(thickness 0.15)
				)
				(justify left bottom)
				(hide yes)
			)
		)
		(property "Tolerance" "~"
			(at 248.92 92.71 0)
			(effects
				(font
					(size 1.27 1.27)
				)
				(justify left bottom)
				(hide yes)
			)
		)
		(property "Current" "1A"
			(at 241.3 114.2999 90)
			(effects
				(font
					(size 1.27 1.27)
					(thickness 0.15)
				)
				(justify right)
				(hide yes)
			)
		)
		(pin "1"
		)
		(pin "2"
		)
		(instances
			(project "k410t-devboard"
				(path ""
					(reference "R310")
					(unit 1)
				)
			)
		)
	)
	(symbol
		(lib_id "antmicroResistors0402:R_0R_0402")
		(at 384.81 161.29 180)
		(unit 1)
		(exclude_from_sim no)
		(in_bom yes)
		(on_board yes)
		(dnp no)
		(property "Reference" "R329"
			(at 382.27 157.48 0)
			(effects
				(font
					(size 1.27 1.27)
				)
			)
		)
		(property "Value" "R_0R_0402"
			(at 364.49 148.59 0)
			(effects
				(font
					(size 1.27 1.27)
					(thickness 0.15)
				)
				(justify left bottom)
				(hide yes)
			)
		)
		(property "Footprint" "antmicro-footprints:R_0402_1005Metric"
			(at 364.49 146.05 0)
			(effects
				(font
					(size 1.27 1.27)
					(thickness 0.15)
				)
				(justify left bottom)
				(hide yes)
			)
		)
		(property "Datasheet" "https://industrial.panasonic.com/cdbs/www-data/pdf/RDA0000/AOA0000C301.pdf"
			(at 364.49 143.51 0)
			(effects
				(font
					(size 1.27 1.27)
					(thickness 0.15)
				)
				(justify left bottom)
				(hide yes)
			)
		)
		(property "Description" ""
			(at 384.81 161.29 0)
			(effects
				(font
					(size 1.27 1.27)
				)
			)
		)
		(property "Manufacturer" "Panasonic"
			(at 364.49 138.43 0)
			(effects
				(font
					(size 1.27 1.27)
					(thickness 0.15)
				)
				(justify left bottom)
				(hide yes)
			)
		)
		(property "MPN" "ERJ2GE0R00X"
			(at 364.49 140.97 0)
			(effects
				(font
					(size 1.27 1.27)
					(thickness 0.15)
				)
				(justify left bottom)
				(hide yes)
			)
		)
		(property "Val" "0R"
			(at 382.27 159.385 0)
			(effects
				(font
					(size 1.27 1.27)
					(thickness 0.15)
				)
			)
		)
		(property "License" "Apache-2.0"
			(at 364.49 135.89 0)
			(effects
				(font
					(size 1.27 1.27)
					(thickness 0.15)
				)
				(justify left bottom)
				(hide yes)
			)
		)
		(property "Author" "Antmicro"
			(at 364.49 133.35 0)
			(effects
				(font
					(size 1.27 1.27)
					(thickness 0.15)
				)
				(justify left bottom)
				(hide yes)
			)
		)
		(property "Tolerance" "~"
			(at 364.49 151.13 0)
			(effects
				(font
					(size 1.27 1.27)
				)
				(justify left bottom)
				(hide yes)
			)
		)
		(property "Current" "1A"
			(at 382.27 157.48 0)
			(effects
				(font
					(size 1.27 1.27)
					(thickness 0.15)
				)
				(hide yes)
			)
		)
		(pin "1"
		)
		(pin "2"
		)
		(instances
			(project "k410t-devboard"
				(path ""
					(reference "R329")
					(unit 1)
				)
			)
		)
	)
	(symbol
		(lib_id "antmicroPMICVoltageRegulatorsLinear:TPS7A20185PDQNR")
		(at 314.96 161.29 0)
		(unit 1)
		(exclude_from_sim no)
		(in_bom yes)
		(on_board yes)
		(dnp no)
		(fields_autoplaced yes)
		(property "Reference" "U38"
			(at 323.85 153.67 0)
			(effects
				(font
					(size 1.27 1.27)
				)
			)
		)
		(property "Value" "TPS7A20185PDQNR"
			(at 323.85 156.21 0)
			(effects
				(font
					(size 1.27 1.27)
				)
				(hide yes)
			)
		)
		(property "Footprint" "antmicro-footprints:XDFN4"
			(at 317.5 175.895 0)
			(effects
				(font
					(size 1.27 1.27)
				)
				(justify left bottom)
				(hide yes)
			)
		)
		(property "Datasheet" "https://www.ti.com/general/docs/suppproductinfo.tsp?distId=26&gotoUrl=https://www.ti.com/lit/gpn/tps7a20"
			(at 318.77 178.435 0)
			(effects
				(font
					(size 1.27 1.27)
				)
				(justify left bottom)
				(hide yes)
			)
		)
		(property "Description" ""
			(at 314.96 161.29 0)
			(effects
				(font
					(size 1.27 1.27)
				)
			)
		)
		(property "MPN" "TPS7A20185PDQNR"
			(at 323.85 156.21 0)
			(effects
				(font
					(size 1.27 1.27)
				)
			)
		)
		(property "Manufacturer" "Texas Instruments"
			(at 327.66 170.815 0)
			(effects
				(font
					(size 1.27 1.27)
				)
				(hide yes)
			)
		)
		(property "Author" "Antmicro"
			(at 347.98 179.07 0)
			(effects
				(font
					(size 1.27 1.27)
					(thickness 0.15)
				)
				(justify left bottom)
				(hide yes)
			)
		)
		(property "License" "Apache-2.0"
			(at 347.98 181.61 0)
			(effects
				(font
					(size 1.27 1.27)
					(thickness 0.15)
				)
				(justify left bottom)
				(hide yes)
			)
		)
		(pin "1"
		)
		(pin "2"
		)
		(pin "3"
		)
		(pin "4"
		)
		(pin "5"
		)
		(instances
			(project "k410t-devboard"
				(path ""
					(reference "U38")
					(unit 1)
				)
			)
		)
	)
	(symbol
		(lib_id "antmicroResistors0402:R_0R_0402")
		(at 203.2 196.85 90)
		(unit 1)
		(exclude_from_sim no)
		(in_bom no)
		(on_board yes)
		(dnp yes)
		(property "Reference" "R306"
			(at 205.74 193.04 90)
			(effects
				(font
					(size 1.27 1.27)
				)
				(justify right)
			)
		)
		(property "Value" "R_0R_0402"
			(at 215.9 176.53 0)
			(effects
				(font
					(size 1.27 1.27)
					(thickness 0.15)
				)
				(justify left bottom)
				(hide yes)
			)
		)
		(property "Footprint" "antmicro-footprints:R_0402_1005Metric"
			(at 218.44 176.53 0)
			(effects
				(font
					(size 1.27 1.27)
					(thickness 0.15)
				)
				(justify left bottom)
				(hide yes)
			)
		)
		(property "Datasheet" "https://industrial.panasonic.com/cdbs/www-data/pdf/RDA0000/AOA0000C301.pdf"
			(at 220.98 176.53 0)
			(effects
				(font
					(size 1.27 1.27)
					(thickness 0.15)
				)
				(justify left bottom)
				(hide yes)
			)
		)
		(property "Description" ""
			(at 203.2 196.85 0)
			(effects
				(font
					(size 1.27 1.27)
				)
			)
		)
		(property "Manufacturer" "Panasonic"
			(at 226.06 176.53 0)
			(effects
				(font
					(size 1.27 1.27)
					(thickness 0.15)
				)
				(justify left bottom)
				(hide yes)
			)
		)
		(property "MPN" "ERJ2GE0R00X"
			(at 223.52 176.53 0)
			(effects
				(font
					(size 1.27 1.27)
					(thickness 0.15)
				)
				(justify left bottom)
				(hide yes)
			)
		)
		(property "Val" "0R"
			(at 205.74 195.58 90)
			(effects
				(font
					(size 1.27 1.27)
					(thickness 0.15)
				)
				(justify right)
			)
		)
		(property "DNP" "DNP"
			(at 203.2 192.405 0)
			(effects
				(font
					(size 1.27 1.27)
				)
				(justify right)
			)
		)
		(property "License" "Apache-2.0"
			(at 228.6 176.53 0)
			(effects
				(font
					(size 1.27 1.27)
					(thickness 0.15)
				)
				(justify left bottom)
				(hide yes)
			)
		)
		(property "Author" "Antmicro"
			(at 231.14 176.53 0)
			(effects
				(font
					(size 1.27 1.27)
					(thickness 0.15)
				)
				(justify left bottom)
				(hide yes)
			)
		)
		(property "Tolerance" "~"
			(at 213.36 176.53 0)
			(effects
				(font
					(size 1.27 1.27)
				)
				(justify left bottom)
				(hide yes)
			)
		)
		(property "Current" "1A"
			(at 205.74 198.1199 90)
			(effects
				(font
					(size 1.27 1.27)
					(thickness 0.15)
				)
				(justify right)
				(hide yes)
			)
		)
		(pin "1"
		)
		(pin "2"
		)
		(instances
			(project "k410t-devboard"
				(path ""
					(reference "R306")
					(unit 1)
				)
			)
		)
	)
	(symbol
		(lib_id "antmicropower:GND")
		(at 314.96 69.85 0)
		(unit 1)
		(exclude_from_sim no)
		(in_bom yes)
		(on_board yes)
		(dnp no)
		(fields_autoplaced yes)
		(property "Reference" "#PWR0420"
			(at 314.96 76.2 0)
			(effects
				(font
					(size 1.27 1.27)
				)
				(hide yes)
			)
		)
		(property "Value" "GND"
			(at 314.96 73.66 0)
			(effects
				(font
					(size 1.27 1.27)
				)
			)
		)
		(property "Footprint" ""
			(at 323.85 77.47 0)
			(effects
				(font
					(size 1.27 1.27)
					(thickness 0.15)
				)
				(justify left bottom)
				(hide yes)
			)
		)
		(property "Datasheet" ""
			(at 323.85 82.55 0)
			(effects
				(font
					(size 1.27 1.27)
					(thickness 0.15)
				)
				(justify left bottom)
				(hide yes)
			)
		)
		(property "Description" ""
			(at 314.96 69.85 0)
			(effects
				(font
					(size 1.27 1.27)
				)
			)
		)
		(property "Author" "Antmicro"
			(at 323.85 77.47 0)
			(effects
				(font
					(size 1.27 1.27)
					(thickness 0.15)
				)
				(justify left bottom)
				(hide yes)
			)
		)
		(property "License" "Apache-2.0"
			(at 323.85 80.01 0)
			(effects
				(font
					(size 1.27 1.27)
					(thickness 0.15)
				)
				(justify left bottom)
				(hide yes)
			)
		)
		(pin "1"
		)
		(instances
			(project "k410t-devboard"
				(path ""
					(reference "#PWR0420")
					(unit 1)
				)
			)
		)
	)
	(symbol
		(lib_id "antmicroResistors0402:R_0R_0402")
		(at 252.73 102.87 90)
		(unit 1)
		(exclude_from_sim no)
		(in_bom no)
		(on_board yes)
		(dnp yes)
		(property "Reference" "R317"
			(at 255.27 99.06 90)
			(effects
				(font
					(size 1.27 1.27)
				)
				(justify right)
			)
		)
		(property "Value" "R_0R_0402"
			(at 265.43 82.55 0)
			(effects
				(font
					(size 1.27 1.27)
					(thickness 0.15)
				)
				(justify left bottom)
				(hide yes)
			)
		)
		(property "Footprint" "antmicro-footprints:R_0402_1005Metric"
			(at 267.97 82.55 0)
			(effects
				(font
					(size 1.27 1.27)
					(thickness 0.15)
				)
				(justify left bottom)
				(hide yes)
			)
		)
		(property "Datasheet" "https://industrial.panasonic.com/cdbs/www-data/pdf/RDA0000/AOA0000C301.pdf"
			(at 270.51 82.55 0)
			(effects
				(font
					(size 1.27 1.27)
					(thickness 0.15)
				)
				(justify left bottom)
				(hide yes)
			)
		)
		(property "Description" ""
			(at 252.73 102.87 0)
			(effects
				(font
					(size 1.27 1.27)
				)
			)
		)
		(property "Manufacturer" "Panasonic"
			(at 275.59 82.55 0)
			(effects
				(font
					(size 1.27 1.27)
					(thickness 0.15)
				)
				(justify left bottom)
				(hide yes)
			)
		)
		(property "MPN" "ERJ2GE0R00X"
			(at 273.05 82.55 0)
			(effects
				(font
					(size 1.27 1.27)
					(thickness 0.15)
				)
				(justify left bottom)
				(hide yes)
			)
		)
		(property "Val" "0R"
			(at 255.27 101.6 90)
			(effects
				(font
					(size 1.27 1.27)
					(thickness 0.15)
				)
				(justify right)
			)
		)
		(property "DNP" "DNP"
			(at 252.73 98.425 0)
			(effects
				(font
					(size 1.27 1.27)
				)
				(justify right)
			)
		)
		(property "License" "Apache-2.0"
			(at 278.13 82.55 0)
			(effects
				(font
					(size 1.27 1.27)
					(thickness 0.15)
				)
				(justify left bottom)
				(hide yes)
			)
		)
		(property "Author" "Antmicro"
			(at 280.67 82.55 0)
			(effects
				(font
					(size 1.27 1.27)
					(thickness 0.15)
				)
				(justify left bottom)
				(hide yes)
			)
		)
		(property "Tolerance" "~"
			(at 262.89 82.55 0)
			(effects
				(font
					(size 1.27 1.27)
				)
				(justify left bottom)
				(hide yes)
			)
		)
		(property "Current" "1A"
			(at 255.27 104.1399 90)
			(effects
				(font
					(size 1.27 1.27)
					(thickness 0.15)
				)
				(justify right)
				(hide yes)
			)
		)
		(pin "1"
		)
		(pin "2"
		)
		(instances
			(project "k410t-devboard"
				(path ""
					(reference "R317")
					(unit 1)
				)
			)
		)
	)
	(symbol
		(lib_id "antmicropower:GND")
		(at 217.17 43.18 0)
		(unit 1)
		(exclude_from_sim no)
		(in_bom yes)
		(on_board yes)
		(dnp no)
		(fields_autoplaced yes)
		(property "Reference" "#PWR0401"
			(at 217.17 49.53 0)
			(effects
				(font
					(size 1.27 1.27)
				)
				(hide yes)
			)
		)
		(property "Value" "GND"
			(at 217.17 46.99 0)
			(effects
				(font
					(size 1.27 1.27)
				)
			)
		)
		(property "Footprint" ""
			(at 226.06 50.8 0)
			(effects
				(font
					(size 1.27 1.27)
					(thickness 0.15)
				)
				(justify left bottom)
				(hide yes)
			)
		)
		(property "Datasheet" ""
			(at 226.06 55.88 0)
			(effects
				(font
					(size 1.27 1.27)
					(thickness 0.15)
				)
				(justify left bottom)
				(hide yes)
			)
		)
		(property "Description" ""
			(at 217.17 43.18 0)
			(effects
				(font
					(size 1.27 1.27)
				)
			)
		)
		(property "Author" "Antmicro"
			(at 226.06 50.8 0)
			(effects
				(font
					(size 1.27 1.27)
					(thickness 0.15)
				)
				(justify left bottom)
				(hide yes)
			)
		)
		(property "License" "Apache-2.0"
			(at 226.06 53.34 0)
			(effects
				(font
					(size 1.27 1.27)
					(thickness 0.15)
				)
				(justify left bottom)
				(hide yes)
			)
		)
		(pin "1"
		)
		(instances
			(project "k410t-devboard"
				(path ""
					(reference "#PWR0401")
					(unit 1)
				)
			)
		)
	)
	(symbol
		(lib_id "antmicroResistors0402:R_0R_0402")
		(at 245.11 140.97 90)
		(unit 1)
		(exclude_from_sim no)
		(in_bom yes)
		(on_board yes)
		(dnp no)
		(fields_autoplaced yes)
		(property "Reference" "R311"
			(at 247.015 137.1599 90)
			(effects
				(font
					(size 1.27 1.27)
				)
				(justify right)
			)
		)
		(property "Value" "R_0R_0402"
			(at 257.81 120.65 0)
			(effects
				(font
					(size 1.27 1.27)
					(thickness 0.15)
				)
				(justify left bottom)
				(hide yes)
			)
		)
		(property "Footprint" "antmicro-footprints:R_0402_1005Metric"
			(at 260.35 120.65 0)
			(effects
				(font
					(size 1.27 1.27)
					(thickness 0.15)
				)
				(justify left bottom)
				(hide yes)
			)
		)
		(property "Datasheet" "https://industrial.panasonic.com/cdbs/www-data/pdf/RDA0000/AOA0000C301.pdf"
			(at 262.89 120.65 0)
			(effects
				(font
					(size 1.27 1.27)
					(thickness 0.15)
				)
				(justify left bottom)
				(hide yes)
			)
		)
		(property "Description" ""
			(at 245.11 140.97 0)
			(effects
				(font
					(size 1.27 1.27)
				)
			)
		)
		(property "Manufacturer" "Panasonic"
			(at 267.97 120.65 0)
			(effects
				(font
					(size 1.27 1.27)
					(thickness 0.15)
				)
				(justify left bottom)
				(hide yes)
			)
		)
		(property "MPN" "ERJ2GE0R00X"
			(at 265.43 120.65 0)
			(effects
				(font
					(size 1.27 1.27)
					(thickness 0.15)
				)
				(justify left bottom)
				(hide yes)
			)
		)
		(property "Val" "0R"
			(at 247.015 139.6999 90)
			(effects
				(font
					(size 1.27 1.27)
					(thickness 0.15)
				)
				(justify right)
			)
		)
		(property "License" "Apache-2.0"
			(at 270.51 120.65 0)
			(effects
				(font
					(size 1.27 1.27)
					(thickness 0.15)
				)
				(justify left bottom)
				(hide yes)
			)
		)
		(property "Author" "Antmicro"
			(at 273.05 120.65 0)
			(effects
				(font
					(size 1.27 1.27)
					(thickness 0.15)
				)
				(justify left bottom)
				(hide yes)
			)
		)
		(property "Tolerance" "~"
			(at 255.27 120.65 0)
			(effects
				(font
					(size 1.27 1.27)
				)
				(justify left bottom)
				(hide yes)
			)
		)
		(property "Current" "1A"
			(at 247.015 140.9699 90)
			(effects
				(font
					(size 1.27 1.27)
					(thickness 0.15)
				)
				(justify right)
				(hide yes)
			)
		)
		(pin "1"
		)
		(pin "2"
		)
		(instances
			(project "k410t-devboard"
				(path ""
					(reference "R311")
					(unit 1)
				)
			)
		)
	)
	(symbol
		(lib_id "antmicropower:GND")
		(at 242.57 219.71 0)
		(unit 1)
		(exclude_from_sim no)
		(in_bom yes)
		(on_board yes)
		(dnp no)
		(fields_autoplaced yes)
		(property "Reference" "#PWR0405"
			(at 242.57 226.06 0)
			(effects
				(font
					(size 1.27 1.27)
				)
				(hide yes)
			)
		)
		(property "Value" "GND"
			(at 242.57 223.52 0)
			(effects
				(font
					(size 1.27 1.27)
				)
			)
		)
		(property "Footprint" ""
			(at 251.46 227.33 0)
			(effects
				(font
					(size 1.27 1.27)
					(thickness 0.15)
				)
				(justify left bottom)
				(hide yes)
			)
		)
		(property "Datasheet" ""
			(at 251.46 232.41 0)
			(effects
				(font
					(size 1.27 1.27)
					(thickness 0.15)
				)
				(justify left bottom)
				(hide yes)
			)
		)
		(property "Description" ""
			(at 242.57 219.71 0)
			(effects
				(font
					(size 1.27 1.27)
				)
			)
		)
		(property "Author" "Antmicro"
			(at 251.46 227.33 0)
			(effects
				(font
					(size 1.27 1.27)
					(thickness 0.15)
				)
				(justify left bottom)
				(hide yes)
			)
		)
		(property "License" "Apache-2.0"
			(at 251.46 229.87 0)
			(effects
				(font
					(size 1.27 1.27)
					(thickness 0.15)
				)
				(justify left bottom)
				(hide yes)
			)
		)
		(pin "1"
		)
		(instances
			(project "k410t-devboard"
				(path ""
					(reference "#PWR0405")
					(unit 1)
				)
			)
		)
	)
	(symbol
		(lib_id "k410t-devboard:Net-Tie_2")
		(at 242.57 217.17 90)
		(unit 1)
		(exclude_from_sim no)
		(in_bom yes)
		(on_board yes)
		(dnp no)
		(fields_autoplaced yes)
		(property "Reference" "NT25"
			(at 241.3 217.17 0)
			(effects
				(font
					(size 1.27 1.27)
				)
				(hide yes)
			)
		)
		(property "Value" "Net-Tie_2"
			(at 240.665 215.2649 90)
			(effects
				(font
					(size 1.27 1.27)
					(thickness 0.15)
				)
				(justify left)
				(hide yes)
			)
		)
		(property "Footprint" "antmicro-footprints:NetTie-2_SMD_Pad0.127mm"
			(at 247.65 195.58 0)
			(effects
				(font
					(size 1.27 1.27)
					(thickness 0.15)
				)
				(justify left bottom)
				(hide yes)
			)
		)
		(property "Datasheet" ""
			(at 250.19 195.58 0)
			(effects
				(font
					(size 1.27 1.27)
					(thickness 0.15)
				)
				(justify left bottom)
				(hide yes)
			)
		)
		(property "Description" ""
			(at 242.57 217.17 0)
			(effects
				(font
					(size 1.27 1.27)
				)
			)
		)
		(property "MPN" ""
			(at 251.46 195.58 0)
			(effects
				(font
					(size 1.27 1.27)
				)
				(justify left)
				(hide yes)
			)
		)
		(property "Manufacturer" ""
			(at 254 195.58 0)
			(effects
				(font
					(size 1.27 1.27)
				)
				(justify left)
				(hide yes)
			)
		)
		(property "Author" "Antmicro"
			(at 257.81 195.58 0)
			(effects
				(font
					(size 1.27 1.27)
					(thickness 0.15)
				)
				(justify left bottom)
				(hide yes)
			)
		)
		(property "License" "Apache-2.0"
			(at 260.35 195.58 0)
			(effects
				(font
					(size 1.27 1.27)
					(thickness 0.15)
				)
				(justify left bottom)
				(hide yes)
			)
		)
		(pin "1"
		)
		(pin "2"
		)
		(instances
			(project "k410t-devboard"
				(path ""
					(reference "NT25")
					(unit 1)
				)
			)
		)
	)
	(symbol
		(lib_id "antmicroResistors0402:R_0R_0402")
		(at 200.66 102.87 90)
		(unit 1)
		(exclude_from_sim no)
		(in_bom no)
		(on_board yes)
		(dnp yes)
		(property "Reference" "R304"
			(at 203.2 99.06 90)
			(effects
				(font
					(size 1.27 1.27)
				)
				(justify right)
			)
		)
		(property "Value" "R_0R_0402"
			(at 213.36 82.55 0)
			(effects
				(font
					(size 1.27 1.27)
					(thickness 0.15)
				)
				(justify left bottom)
				(hide yes)
			)
		)
		(property "Footprint" "antmicro-footprints:R_0402_1005Metric"
			(at 215.9 82.55 0)
			(effects
				(font
					(size 1.27 1.27)
					(thickness 0.15)
				)
				(justify left bottom)
				(hide yes)
			)
		)
		(property "Datasheet" "https://industrial.panasonic.com/cdbs/www-data/pdf/RDA0000/AOA0000C301.pdf"
			(at 218.44 82.55 0)
			(effects
				(font
					(size 1.27 1.27)
					(thickness 0.15)
				)
				(justify left bottom)
				(hide yes)
			)
		)
		(property "Description" ""
			(at 200.66 102.87 0)
			(effects
				(font
					(size 1.27 1.27)
				)
			)
		)
		(property "Manufacturer" "Panasonic"
			(at 223.52 82.55 0)
			(effects
				(font
					(size 1.27 1.27)
					(thickness 0.15)
				)
				(justify left bottom)
				(hide yes)
			)
		)
		(property "MPN" "ERJ2GE0R00X"
			(at 220.98 82.55 0)
			(effects
				(font
					(size 1.27 1.27)
					(thickness 0.15)
				)
				(justify left bottom)
				(hide yes)
			)
		)
		(property "Val" "0R"
			(at 203.2 101.6 90)
			(effects
				(font
					(size 1.27 1.27)
					(thickness 0.15)
				)
				(justify right)
			)
		)
		(property "DNP" "DNP"
			(at 200.66 98.425 0)
			(effects
				(font
					(size 1.27 1.27)
				)
				(justify right)
			)
		)
		(property "License" "Apache-2.0"
			(at 226.06 82.55 0)
			(effects
				(font
					(size 1.27 1.27)
					(thickness 0.15)
				)
				(justify left bottom)
				(hide yes)
			)
		)
		(property "Author" "Antmicro"
			(at 228.6 82.55 0)
			(effects
				(font
					(size 1.27 1.27)
					(thickness 0.15)
				)
				(justify left bottom)
				(hide yes)
			)
		)
		(property "Tolerance" "~"
			(at 210.82 82.55 0)
			(effects
				(font
					(size 1.27 1.27)
				)
				(justify left bottom)
				(hide yes)
			)
		)
		(property "Current" "1A"
			(at 203.2 104.1399 90)
			(effects
				(font
					(size 1.27 1.27)
					(thickness 0.15)
				)
				(justify right)
				(hide yes)
			)
		)
		(pin "1"
		)
		(pin "2"
		)
		(instances
			(project "k410t-devboard"
				(path ""
					(reference "R304")
					(unit 1)
				)
			)
		)
	)
	(symbol
		(lib_id "antmicroPushbuttonSwitches:SW_KMR211NGLFS_SMD")
		(at 91.44 46.99 0)
		(unit 1)
		(exclude_from_sim no)
		(in_bom yes)
		(on_board yes)
		(dnp no)
		(property "Reference" "S6"
			(at 96.52 39.37 0)
			(effects
				(font
					(size 1.27 1.27)
				)
			)
		)
		(property "Value" "SW_KMR211NGLFS_SMD"
			(at 96.52 51.435 0)
			(effects
				(font
					(size 1.27 1.27)
					(thickness 0.15)
				)
				(hide yes)
			)
		)
		(property "Footprint" "antmicro-footprints:SW_KMR211NGLFS_SMD"
			(at 116.84 54.61 0)
			(effects
				(font
					(size 1.27 1.27)
					(thickness 0.15)
				)
				(justify left bottom)
				(hide yes)
			)
		)
		(property "Datasheet" "http://www.farnell.com/datasheets/2631211.pdf"
			(at 116.84 57.15 0)
			(effects
				(font
					(size 1.27 1.27)
					(thickness 0.15)
				)
				(justify left bottom)
				(hide yes)
			)
		)
		(property "Description" ""
			(at 91.44 46.99 0)
			(effects
				(font
					(size 1.27 1.27)
				)
			)
		)
		(property "MPN" "KMR211NGLFS"
			(at 96.52 41.91 0)
			(effects
				(font
					(size 1.27 1.27)
					(thickness 0.15)
				)
			)
		)
		(property "Manufacturer" "C&K"
			(at 116.84 62.23 0)
			(effects
				(font
					(size 1.27 1.27)
					(thickness 0.15)
				)
				(justify left bottom)
				(hide yes)
			)
		)
		(property "Author" "Antmicro"
			(at 116.84 64.77 0)
			(effects
				(font
					(size 1.27 1.27)
					(thickness 0.15)
				)
				(justify left bottom)
				(hide yes)
			)
		)
		(property "License" "Apache-2.0"
			(at 116.84 67.31 0)
			(effects
				(font
					(size 1.27 1.27)
					(thickness 0.15)
				)
				(justify left bottom)
				(hide yes)
			)
		)
		(pin "1"
		)
		(pin "2"
		)
		(pin "3"
		)
		(pin "4"
		)
		(instances
			(project "k410t-devboard"
				(path ""
					(reference "S6")
					(unit 1)
				)
			)
		)
	)
	(symbol
		(lib_id "antmicroCapacitors0402:C_10u_0402")
		(at 350.52 120.65 90)
		(unit 1)
		(exclude_from_sim no)
		(in_bom yes)
		(on_board yes)
		(dnp no)
		(property "Reference" "C353"
			(at 351.155 116.205 90)
			(effects
				(font
					(size 1.27 1.27)
				)
				(justify right)
			)
		)
		(property "Value" "C_10u_0402"
			(at 360.68 100.33 0)
			(effects
				(font
					(size 1.27 1.27)
					(thickness 0.15)
				)
				(justify left bottom)
				(hide yes)
			)
		)
		(property "Footprint" "antmicro-footprints:C_0402_1005Metric"
			(at 363.22 100.33 0)
			(effects
				(font
					(size 1.27 1.27)
					(thickness 0.15)
				)
				(justify left bottom)
				(hide yes)
			)
		)
		(property "Datasheet" "https://www.yageo.com/en/Chart/Download/pdf/CC0402MRX5R5BB106"
			(at 365.76 100.33 0)
			(effects
				(font
					(size 1.27 1.27)
					(thickness 0.15)
				)
				(justify left bottom)
				(hide yes)
			)
		)
		(property "Description" ""
			(at 350.52 120.65 0)
			(effects
				(font
					(size 1.27 1.27)
				)
			)
		)
		(property "Manufacturer" "YAGEO"
			(at 370.84 100.33 0)
			(effects
				(font
					(size 1.27 1.27)
					(thickness 0.15)
				)
				(justify left bottom)
				(hide yes)
			)
		)
		(property "MPN" "CC0402MRX5R5BB106"
			(at 368.3 100.33 0)
			(effects
				(font
					(size 1.27 1.27)
					(thickness 0.15)
				)
				(justify left bottom)
				(hide yes)
			)
		)
		(property "Val" "10u"
			(at 351.155 120.015 90)
			(effects
				(font
					(size 1.27 1.27)
					(thickness 0.15)
				)
				(justify right)
			)
		)
		(property "License" "Apache-2.0"
			(at 373.38 100.33 0)
			(effects
				(font
					(size 1.27 1.27)
					(thickness 0.15)
				)
				(justify left bottom)
				(hide yes)
			)
		)
		(property "Author" "Antmicro"
			(at 375.92 100.33 0)
			(effects
				(font
					(size 1.27 1.27)
					(thickness 0.15)
				)
				(justify left bottom)
				(hide yes)
			)
		)
		(property "Voltage" ""
			(at 378.46 100.33 0)
			(effects
				(font
					(size 1.27 1.27)
				)
				(justify left bottom)
				(hide yes)
			)
		)
		(property "Dielectric" ""
			(at 381 100.33 0)
			(effects
				(font
					(size 1.27 1.27)
				)
				(justify left bottom)
				(hide yes)
			)
		)
		(pin "1"
		)
		(pin "2"
		)
		(instances
			(project "k410t-devboard"
				(path ""
					(reference "C353")
					(unit 1)
				)
			)
		)
	)
	(symbol
		(lib_id "antmicroCapacitors0402:C_22n_0402")
		(at 350.52 76.2 90)
		(unit 1)
		(exclude_from_sim no)
		(in_bom yes)
		(on_board yes)
		(dnp no)
		(fields_autoplaced yes)
		(property "Reference" "C354"
			(at 353.695 72.3835 90)
			(effects
				(font
					(size 1.27 1.27)
				)
				(justify right)
			)
		)
		(property "Value" "C_22n_0402"
			(at 360.68 55.88 0)
			(effects
				(font
					(size 1.27 1.27)
					(thickness 0.15)
				)
				(justify left bottom)
				(hide yes)
			)
		)
		(property "Footprint" "antmicro-footprints:C_0402_1005Metric"
			(at 363.22 55.88 0)
			(effects
				(font
					(size 1.27 1.27)
					(thickness 0.15)
				)
				(justify left bottom)
				(hide yes)
			)
		)
		(property "Datasheet" "https://www.murata.com/products/productdetail?partno=GCM155R71H223MA55%23"
			(at 365.76 55.88 0)
			(effects
				(font
					(size 1.27 1.27)
					(thickness 0.15)
				)
				(justify left bottom)
				(hide yes)
			)
		)
		(property "Description" ""
			(at 350.52 76.2 0)
			(effects
				(font
					(size 1.27 1.27)
				)
			)
		)
		(property "Manufacturer" "Murata"
			(at 370.84 55.88 0)
			(effects
				(font
					(size 1.27 1.27)
					(thickness 0.15)
				)
				(justify left bottom)
				(hide yes)
			)
		)
		(property "MPN" "GCM155R71H223MA55D"
			(at 368.3 55.88 0)
			(effects
				(font
					(size 1.27 1.27)
					(thickness 0.15)
				)
				(justify left bottom)
				(hide yes)
			)
		)
		(property "Val" "22n"
			(at 353.695 74.9235 90)
			(effects
				(font
					(size 1.27 1.27)
					(thickness 0.15)
				)
				(justify right)
			)
		)
		(property "License" "Apache-2.0"
			(at 373.38 55.88 0)
			(effects
				(font
					(size 1.27 1.27)
					(thickness 0.15)
				)
				(justify left bottom)
				(hide yes)
			)
		)
		(property "Author" "Antmicro"
			(at 375.92 55.88 0)
			(effects
				(font
					(size 1.27 1.27)
					(thickness 0.15)
				)
				(justify left bottom)
				(hide yes)
			)
		)
		(property "Voltage" ""
			(at 378.46 55.88 0)
			(effects
				(font
					(size 1.27 1.27)
				)
				(justify left bottom)
				(hide yes)
			)
		)
		(property "Dielectric" ""
			(at 381 55.88 0)
			(effects
				(font
					(size 1.27 1.27)
				)
				(justify left bottom)
				(hide yes)
			)
		)
		(pin "1"
		)
		(pin "2"
		)
		(instances
			(project "k410t-devboard"
				(path ""
					(reference "C354")
					(unit 1)
				)
			)
		)
	)
	(symbol
		(lib_id "antmicroResistors0402:R_4k7_0402")
		(at 317.5 124.46 90)
		(unit 1)
		(exclude_from_sim no)
		(in_bom yes)
		(on_board yes)
		(dnp no)
		(fields_autoplaced yes)
		(property "Reference" "R325"
			(at 320.04 120.6499 90)
			(effects
				(font
					(size 1.27 1.27)
				)
				(justify right)
			)
		)
		(property "Value" "R_4k7_0402"
			(at 330.2 104.14 0)
			(effects
				(font
					(size 1.27 1.27)
					(thickness 0.15)
				)
				(justify left bottom)
				(hide yes)
			)
		)
		(property "Footprint" "antmicro-footprints:R_0402_1005Metric"
			(at 332.74 104.14 0)
			(effects
				(font
					(size 1.27 1.27)
					(thickness 0.15)
				)
				(justify left bottom)
				(hide yes)
			)
		)
		(property "Datasheet" "https://www.bourns.com/docs/product-datasheets/cr.pdf"
			(at 335.28 104.14 0)
			(effects
				(font
					(size 1.27 1.27)
					(thickness 0.15)
				)
				(justify left bottom)
				(hide yes)
			)
		)
		(property "Description" ""
			(at 317.5 124.46 0)
			(effects
				(font
					(size 1.27 1.27)
				)
			)
		)
		(property "Manufacturer" "Bourns"
			(at 340.36 104.14 0)
			(effects
				(font
					(size 1.27 1.27)
					(thickness 0.15)
				)
				(justify left bottom)
				(hide yes)
			)
		)
		(property "MPN" "CR0402-FX-4701GLF"
			(at 337.82 104.14 0)
			(effects
				(font
					(size 1.27 1.27)
					(thickness 0.15)
				)
				(justify left bottom)
				(hide yes)
			)
		)
		(property "Val" "4k7"
			(at 320.04 123.1899 90)
			(effects
				(font
					(size 1.27 1.27)
					(thickness 0.15)
				)
				(justify right)
			)
		)
		(property "License" "Apache-2.0"
			(at 342.9 104.14 0)
			(effects
				(font
					(size 1.27 1.27)
					(thickness 0.15)
				)
				(justify left bottom)
				(hide yes)
			)
		)
		(property "Author" "Antmicro"
			(at 345.44 104.14 0)
			(effects
				(font
					(size 1.27 1.27)
					(thickness 0.15)
				)
				(justify left bottom)
				(hide yes)
			)
		)
		(property "Tolerance" "1%"
			(at 327.66 104.14 0)
			(effects
				(font
					(size 1.27 1.27)
				)
				(justify left bottom)
				(hide yes)
			)
		)
		(pin "1"
		)
		(pin "2"
		)
		(instances
			(project "k410t-devboard"
				(path ""
					(reference "R325")
					(unit 1)
				)
			)
		)
	)
	(symbol
		(lib_id "antmicroResistors0402:R_0R_0402")
		(at 187.96 143.51 90)
		(unit 1)
		(exclude_from_sim no)
		(in_bom yes)
		(on_board yes)
		(dnp no)
		(fields_autoplaced yes)
		(property "Reference" "R298"
			(at 189.865 139.6999 90)
			(effects
				(font
					(size 1.27 1.27)
				)
				(justify right)
			)
		)
		(property "Value" "R_0R_0402"
			(at 200.66 123.19 0)
			(effects
				(font
					(size 1.27 1.27)
					(thickness 0.15)
				)
				(justify left bottom)
				(hide yes)
			)
		)
		(property "Footprint" "antmicro-footprints:R_0402_1005Metric"
			(at 203.2 123.19 0)
			(effects
				(font
					(size 1.27 1.27)
					(thickness 0.15)
				)
				(justify left bottom)
				(hide yes)
			)
		)
		(property "Datasheet" "https://industrial.panasonic.com/cdbs/www-data/pdf/RDA0000/AOA0000C301.pdf"
			(at 205.74 123.19 0)
			(effects
				(font
					(size 1.27 1.27)
					(thickness 0.15)
				)
				(justify left bottom)
				(hide yes)
			)
		)
		(property "Description" ""
			(at 187.96 143.51 0)
			(effects
				(font
					(size 1.27 1.27)
				)
			)
		)
		(property "Manufacturer" "Panasonic"
			(at 210.82 123.19 0)
			(effects
				(font
					(size 1.27 1.27)
					(thickness 0.15)
				)
				(justify left bottom)
				(hide yes)
			)
		)
		(property "MPN" "ERJ2GE0R00X"
			(at 208.28 123.19 0)
			(effects
				(font
					(size 1.27 1.27)
					(thickness 0.15)
				)
				(justify left bottom)
				(hide yes)
			)
		)
		(property "Val" "0R"
			(at 189.865 142.2399 90)
			(effects
				(font
					(size 1.27 1.27)
					(thickness 0.15)
				)
				(justify right)
			)
		)
		(property "License" "Apache-2.0"
			(at 213.36 123.19 0)
			(effects
				(font
					(size 1.27 1.27)
					(thickness 0.15)
				)
				(justify left bottom)
				(hide yes)
			)
		)
		(property "Author" "Antmicro"
			(at 215.9 123.19 0)
			(effects
				(font
					(size 1.27 1.27)
					(thickness 0.15)
				)
				(justify left bottom)
				(hide yes)
			)
		)
		(property "Tolerance" "~"
			(at 198.12 123.19 0)
			(effects
				(font
					(size 1.27 1.27)
				)
				(justify left bottom)
				(hide yes)
			)
		)
		(property "Current" "1A"
			(at 189.865 143.5099 90)
			(effects
				(font
					(size 1.27 1.27)
					(thickness 0.15)
				)
				(justify right)
				(hide yes)
			)
		)
		(pin "1"
		)
		(pin "2"
		)
		(instances
			(project "k410t-devboard"
				(path ""
					(reference "R298")
					(unit 1)
				)
			)
		)
	)
	(symbol
		(lib_id "antmicroResistors0402:R_0R_0402")
		(at 242.57 208.28 90)
		(unit 1)
		(exclude_from_sim no)
		(in_bom no)
		(on_board yes)
		(dnp yes)
		(property "Reference" "R314"
			(at 244.475 204.47 90)
			(effects
				(font
					(size 1.27 1.27)
				)
				(justify right)
			)
		)
		(property "Value" "R_0R_0402"
			(at 255.27 187.96 0)
			(effects
				(font
					(size 1.27 1.27)
					(thickness 0.15)
				)
				(justify left bottom)
				(hide yes)
			)
		)
		(property "Footprint" "antmicro-footprints:R_0402_1005Metric"
			(at 257.81 187.96 0)
			(effects
				(font
					(size 1.27 1.27)
					(thickness 0.15)
				)
				(justify left bottom)
				(hide yes)
			)
		)
		(property "Datasheet" "https://industrial.panasonic.com/cdbs/www-data/pdf/RDA0000/AOA0000C301.pdf"
			(at 260.35 187.96 0)
			(effects
				(font
					(size 1.27 1.27)
					(thickness 0.15)
				)
				(justify left bottom)
				(hide yes)
			)
		)
		(property "Description" ""
			(at 242.57 208.28 0)
			(effects
				(font
					(size 1.27 1.27)
				)
			)
		)
		(property "Manufacturer" "Panasonic"
			(at 265.43 187.96 0)
			(effects
				(font
					(size 1.27 1.27)
					(thickness 0.15)
				)
				(justify left bottom)
				(hide yes)
			)
		)
		(property "MPN" "ERJ2GE0R00X"
			(at 262.89 187.96 0)
			(effects
				(font
					(size 1.27 1.27)
					(thickness 0.15)
				)
				(justify left bottom)
				(hide yes)
			)
		)
		(property "Val" "0R"
			(at 244.475 207.01 90)
			(effects
				(font
					(size 1.27 1.27)
					(thickness 0.15)
				)
				(justify right)
			)
		)
		(property "DNP" "DNP"
			(at 242.57 203.835 0)
			(effects
				(font
					(size 1.27 1.27)
				)
				(justify right)
			)
		)
		(property "License" "Apache-2.0"
			(at 267.97 187.96 0)
			(effects
				(font
					(size 1.27 1.27)
					(thickness 0.15)
				)
				(justify left bottom)
				(hide yes)
			)
		)
		(property "Author" "Antmicro"
			(at 270.51 187.96 0)
			(effects
				(font
					(size 1.27 1.27)
					(thickness 0.15)
				)
				(justify left bottom)
				(hide yes)
			)
		)
		(property "Tolerance" "~"
			(at 252.73 187.96 0)
			(effects
				(font
					(size 1.27 1.27)
				)
				(justify left bottom)
				(hide yes)
			)
		)
		(property "Current" "1A"
			(at 244.475 209.5499 90)
			(effects
				(font
					(size 1.27 1.27)
					(thickness 0.15)
				)
				(justify right)
				(hide yes)
			)
		)
		(pin "1"
		)
		(pin "2"
		)
		(instances
			(project "k410t-devboard"
				(path ""
					(reference "R314")
					(unit 1)
				)
			)
		)
	)
	(symbol
		(lib_id "antmicroResistors0603:R_0R_22.4A_0603")
		(at 378.46 215.9 0)
		(unit 1)
		(exclude_from_sim no)
		(in_bom yes)
		(on_board yes)
		(dnp no)
		(fields_autoplaced yes)
		(property "Reference" "R330"
			(at 381 207.01 0)
			(effects
				(font
					(size 1.27 1.27)
				)
			)
		)
		(property "Value" "R_0R_22.4A_0603"
			(at 381 209.55 0)
			(effects
				(font
					(size 1.27 1.27)
					(thickness 0.15)
				)
				(hide yes)
			)
		)
		(property "Footprint" "antmicro-footprints:R_0603_1608Metric"
			(at 401.32 228.6 0)
			(effects
				(font
					(size 1.27 1.27)
					(thickness 0.15)
				)
				(justify left bottom)
				(hide yes)
			)
		)
		(property "Datasheet" "https://fscdn.rohm.com/en/products/databook/datasheet/passive/resistor/chip_resistor/pmr-jpw-e.pdf"
			(at 401.32 231.14 0)
			(effects
				(font
					(size 1.27 1.27)
					(thickness 0.15)
				)
				(justify left bottom)
				(hide yes)
			)
		)
		(property "Description" ""
			(at 378.46 215.9 0)
			(effects
				(font
					(size 1.27 1.27)
				)
			)
		)
		(property "Manufacturer" "ROHM Semiconductor"
			(at 401.32 233.68 0)
			(effects
				(font
					(size 1.27 1.27)
					(thickness 0.15)
				)
				(justify left bottom)
				(hide yes)
			)
		)
		(property "MPN" "PMR03EZPJ000"
			(at 401.32 236.22 0)
			(effects
				(font
					(size 1.27 1.27)
					(thickness 0.15)
				)
				(justify left bottom)
				(hide yes)
			)
		)
		(property "Val" "0R"
			(at 381 209.55 0)
			(effects
				(font
					(size 1.27 1.27)
					(thickness 0.15)
				)
			)
		)
		(property "Author" "Antmicro"
			(at 401.32 238.76 0)
			(effects
				(font
					(size 1.27 1.27)
					(thickness 0.15)
				)
				(justify left bottom)
				(hide yes)
			)
		)
		(property "License" "Apache-2.0"
			(at 401.32 241.3 0)
			(effects
				(font
					(size 1.27 1.27)
					(thickness 0.15)
				)
				(justify left bottom)
				(hide yes)
			)
		)
		(property "Max. Curr." "22.4A"
			(at 381 212.09 0)
			(effects
				(font
					(size 1.27 1.27)
					(thickness 0.15)
				)
			)
		)
		(property "Tolerance" "template_tolerance"
			(at 398.78 226.06 0)
			(effects
				(font
					(size 1.27 1.27)
				)
				(justify left bottom)
				(hide yes)
			)
		)
		(pin "1"
		)
		(pin "2"
		)
		(instances
			(project "k410t-devboard"
				(path ""
					(reference "R330")
					(unit 1)
				)
			)
		)
	)
	(symbol
		(lib_id "antmicroResistors0402:R_0R_0402")
		(at 190.5 240.03 90)
		(unit 1)
		(exclude_from_sim no)
		(in_bom yes)
		(on_board yes)
		(dnp no)
		(fields_autoplaced yes)
		(property "Reference" "R302"
			(at 193.04 236.2199 90)
			(effects
				(font
					(size 1.27 1.27)
				)
				(justify right)
			)
		)
		(property "Value" "R_0R_0402"
			(at 203.2 219.71 0)
			(effects
				(font
					(size 1.27 1.27)
					(thickness 0.15)
				)
				(justify left bottom)
				(hide yes)
			)
		)
		(property "Footprint" "antmicro-footprints:R_0402_1005Metric"
			(at 205.74 219.71 0)
			(effects
				(font
					(size 1.27 1.27)
					(thickness 0.15)
				)
				(justify left bottom)
				(hide yes)
			)
		)
		(property "Datasheet" "https://industrial.panasonic.com/cdbs/www-data/pdf/RDA0000/AOA0000C301.pdf"
			(at 208.28 219.71 0)
			(effects
				(font
					(size 1.27 1.27)
					(thickness 0.15)
				)
				(justify left bottom)
				(hide yes)
			)
		)
		(property "Description" ""
			(at 190.5 240.03 0)
			(effects
				(font
					(size 1.27 1.27)
				)
			)
		)
		(property "Manufacturer" "Panasonic"
			(at 213.36 219.71 0)
			(effects
				(font
					(size 1.27 1.27)
					(thickness 0.15)
				)
				(justify left bottom)
				(hide yes)
			)
		)
		(property "MPN" "ERJ2GE0R00X"
			(at 210.82 219.71 0)
			(effects
				(font
					(size 1.27 1.27)
					(thickness 0.15)
				)
				(justify left bottom)
				(hide yes)
			)
		)
		(property "Val" "0R"
			(at 193.04 238.7599 90)
			(effects
				(font
					(size 1.27 1.27)
					(thickness 0.15)
				)
				(justify right)
			)
		)
		(property "License" "Apache-2.0"
			(at 215.9 219.71 0)
			(effects
				(font
					(size 1.27 1.27)
					(thickness 0.15)
				)
				(justify left bottom)
				(hide yes)
			)
		)
		(property "Author" "Antmicro"
			(at 218.44 219.71 0)
			(effects
				(font
					(size 1.27 1.27)
					(thickness 0.15)
				)
				(justify left bottom)
				(hide yes)
			)
		)
		(property "Tolerance" "~"
			(at 200.66 219.71 0)
			(effects
				(font
					(size 1.27 1.27)
				)
				(justify left bottom)
				(hide yes)
			)
		)
		(property "Current" "1A"
			(at 193.04 240.0299 90)
			(effects
				(font
					(size 1.27 1.27)
					(thickness 0.15)
				)
				(justify right)
				(hide yes)
			)
		)
		(pin "1"
		)
		(pin "2"
		)
		(instances
			(project "k410t-devboard"
				(path ""
					(reference "R302")
					(unit 1)
				)
			)
		)
	)
	(symbol
		(lib_id "antmicropower:GND")
		(at 232.41 59.69 0)
		(unit 1)
		(exclude_from_sim no)
		(in_bom yes)
		(on_board yes)
		(dnp no)
		(fields_autoplaced yes)
		(property "Reference" "#PWR0402"
			(at 232.41 66.04 0)
			(effects
				(font
					(size 1.27 1.27)
				)
				(hide yes)
			)
		)
		(property "Value" "GND"
			(at 232.41 63.5 0)
			(effects
				(font
					(size 1.27 1.27)
				)
			)
		)
		(property "Footprint" ""
			(at 241.3 67.31 0)
			(effects
				(font
					(size 1.27 1.27)
					(thickness 0.15)
				)
				(justify left bottom)
				(hide yes)
			)
		)
		(property "Datasheet" ""
			(at 241.3 72.39 0)
			(effects
				(font
					(size 1.27 1.27)
					(thickness 0.15)
				)
				(justify left bottom)
				(hide yes)
			)
		)
		(property "Description" ""
			(at 232.41 59.69 0)
			(effects
				(font
					(size 1.27 1.27)
				)
			)
		)
		(property "Author" "Antmicro"
			(at 241.3 67.31 0)
			(effects
				(font
					(size 1.27 1.27)
					(thickness 0.15)
				)
				(justify left bottom)
				(hide yes)
			)
		)
		(property "License" "Apache-2.0"
			(at 241.3 69.85 0)
			(effects
				(font
					(size 1.27 1.27)
					(thickness 0.15)
				)
				(justify left bottom)
				(hide yes)
			)
		)
		(pin "1"
		)
		(instances
			(project "k410t-devboard"
				(path ""
					(reference "#PWR0402")
					(unit 1)
				)
			)
		)
	)
	(symbol
		(lib_id "antmicroResistors0402:R_0R_0402")
		(at 238.76 102.87 90)
		(unit 1)
		(exclude_from_sim no)
		(in_bom yes)
		(on_board yes)
		(dnp no)
		(fields_autoplaced yes)
		(property "Reference" "R309"
			(at 241.3 99.0599 90)
			(effects
				(font
					(size 1.27 1.27)
				)
				(justify right)
			)
		)
		(property "Value" "R_0R_0402"
			(at 251.46 82.55 0)
			(effects
				(font
					(size 1.27 1.27)
					(thickness 0.15)
				)
				(justify left bottom)
				(hide yes)
			)
		)
		(property "Footprint" "antmicro-footprints:R_0402_1005Metric"
			(at 254 82.55 0)
			(effects
				(font
					(size 1.27 1.27)
					(thickness 0.15)
				)
				(justify left bottom)
				(hide yes)
			)
		)
		(property "Datasheet" "https://industrial.panasonic.com/cdbs/www-data/pdf/RDA0000/AOA0000C301.pdf"
			(at 256.54 82.55 0)
			(effects
				(font
					(size 1.27 1.27)
					(thickness 0.15)
				)
				(justify left bottom)
				(hide yes)
			)
		)
		(property "Description" ""
			(at 238.76 102.87 0)
			(effects
				(font
					(size 1.27 1.27)
				)
			)
		)
		(property "Manufacturer" "Panasonic"
			(at 261.62 82.55 0)
			(effects
				(font
					(size 1.27 1.27)
					(thickness 0.15)
				)
				(justify left bottom)
				(hide yes)
			)
		)
		(property "MPN" "ERJ2GE0R00X"
			(at 259.08 82.55 0)
			(effects
				(font
					(size 1.27 1.27)
					(thickness 0.15)
				)
				(justify left bottom)
				(hide yes)
			)
		)
		(property "Val" "0R"
			(at 241.3 101.5999 90)
			(effects
				(font
					(size 1.27 1.27)
					(thickness 0.15)
				)
				(justify right)
			)
		)
		(property "License" "Apache-2.0"
			(at 264.16 82.55 0)
			(effects
				(font
					(size 1.27 1.27)
					(thickness 0.15)
				)
				(justify left bottom)
				(hide yes)
			)
		)
		(property "Author" "Antmicro"
			(at 266.7 82.55 0)
			(effects
				(font
					(size 1.27 1.27)
					(thickness 0.15)
				)
				(justify left bottom)
				(hide yes)
			)
		)
		(property "Tolerance" "~"
			(at 248.92 82.55 0)
			(effects
				(font
					(size 1.27 1.27)
				)
				(justify left bottom)
				(hide yes)
			)
		)
		(property "Current" "1A"
			(at 241.3 102.8699 90)
			(effects
				(font
					(size 1.27 1.27)
					(thickness 0.15)
				)
				(justify right)
				(hide yes)
			)
		)
		(pin "1"
		)
		(pin "2"
		)
		(instances
			(project "k410t-devboard"
				(path ""
					(reference "R309")
					(unit 1)
				)
			)
		)
	)
	(symbol
		(lib_id "antmicroResistors0603:R_0R_22.4A_0603")
		(at 134.62 247.65 0)
		(unit 1)
		(exclude_from_sim no)
		(in_bom yes)
		(on_board yes)
		(dnp no)
		(fields_autoplaced yes)
		(property "Reference" "R292"
			(at 137.16 238.76 0)
			(effects
				(font
					(size 1.27 1.27)
				)
			)
		)
		(property "Value" "R_0R_22.4A_0603"
			(at 157.48 255.27 0)
			(effects
				(font
					(size 1.27 1.27)
					(thickness 0.15)
				)
				(justify left bottom)
				(hide yes)
			)
		)
		(property "Footprint" "antmicro-footprints:R_0603_1608Metric"
			(at 157.48 260.35 0)
			(effects
				(font
					(size 1.27 1.27)
					(thickness 0.15)
				)
				(justify left bottom)
				(hide yes)
			)
		)
		(property "Datasheet" "https://fscdn.rohm.com/en/products/databook/datasheet/passive/resistor/chip_resistor/pmr-jpw-e.pdf"
			(at 157.48 262.89 0)
			(effects
				(font
					(size 1.27 1.27)
					(thickness 0.15)
				)
				(justify left bottom)
				(hide yes)
			)
		)
		(property "Description" ""
			(at 134.62 247.65 0)
			(effects
				(font
					(size 1.27 1.27)
				)
			)
		)
		(property "Manufacturer" "ROHM Semiconductor"
			(at 157.48 265.43 0)
			(effects
				(font
					(size 1.27 1.27)
					(thickness 0.15)
				)
				(justify left bottom)
				(hide yes)
			)
		)
		(property "MPN" "PMR03EZPJ000"
			(at 157.48 267.97 0)
			(effects
				(font
					(size 1.27 1.27)
					(thickness 0.15)
				)
				(justify left bottom)
				(hide yes)
			)
		)
		(property "Val" "0R"
			(at 137.16 241.3 0)
			(effects
				(font
					(size 1.27 1.27)
					(thickness 0.15)
				)
			)
		)
		(property "Author" "Antmicro"
			(at 157.48 270.51 0)
			(effects
				(font
					(size 1.27 1.27)
					(thickness 0.15)
				)
				(justify left bottom)
				(hide yes)
			)
		)
		(property "License" "Apache-2.0"
			(at 157.48 273.05 0)
			(effects
				(font
					(size 1.27 1.27)
					(thickness 0.15)
				)
				(justify left bottom)
				(hide yes)
			)
		)
		(property "Max. Curr." "22.4A"
			(at 137.16 243.84 0)
			(effects
				(font
					(size 1.27 1.27)
					(thickness 0.15)
				)
			)
		)
		(property "Tolerance" "template_tolerance"
			(at 154.94 257.81 0)
			(effects
				(font
					(size 1.27 1.27)
				)
				(justify left bottom)
				(hide yes)
			)
		)
		(pin "1"
		)
		(pin "2"
		)
		(instances
			(project "k410t-devboard"
				(path ""
					(reference "R292")
					(unit 1)
				)
			)
		)
	)
	(symbol
		(lib_id "antmicropower:GND")
		(at 119.38 127 0)
		(unit 1)
		(exclude_from_sim no)
		(in_bom yes)
		(on_board yes)
		(dnp no)
		(fields_autoplaced yes)
		(property "Reference" "#PWR0376"
			(at 119.38 133.35 0)
			(effects
				(font
					(size 1.27 1.27)
				)
				(hide yes)
			)
		)
		(property "Value" "GND"
			(at 119.38 130.81 0)
			(effects
				(font
					(size 1.27 1.27)
				)
			)
		)
		(property "Footprint" ""
			(at 128.27 134.62 0)
			(effects
				(font
					(size 1.27 1.27)
					(thickness 0.15)
				)
				(justify left bottom)
				(hide yes)
			)
		)
		(property "Datasheet" ""
			(at 128.27 139.7 0)
			(effects
				(font
					(size 1.27 1.27)
					(thickness 0.15)
				)
				(justify left bottom)
				(hide yes)
			)
		)
		(property "Description" ""
			(at 119.38 127 0)
			(effects
				(font
					(size 1.27 1.27)
				)
			)
		)
		(property "Author" "Antmicro"
			(at 128.27 134.62 0)
			(effects
				(font
					(size 1.27 1.27)
					(thickness 0.15)
				)
				(justify left bottom)
				(hide yes)
			)
		)
		(property "License" "Apache-2.0"
			(at 128.27 137.16 0)
			(effects
				(font
					(size 1.27 1.27)
					(thickness 0.15)
				)
				(justify left bottom)
				(hide yes)
			)
		)
		(pin "1"
		)
		(instances
			(project "k410t-devboard"
				(path ""
					(reference "#PWR0376")
					(unit 1)
				)
			)
		)
	)
	(symbol
		(lib_id "antmicroResistors0402:R_0R_0402")
		(at 190.5 250.19 90)
		(unit 1)
		(exclude_from_sim no)
		(in_bom no)
		(on_board yes)
		(dnp yes)
		(property "Reference" "R303"
			(at 193.04 246.38 90)
			(effects
				(font
					(size 1.27 1.27)
				)
				(justify right)
			)
		)
		(property "Value" "R_0R_0402"
			(at 203.2 229.87 0)
			(effects
				(font
					(size 1.27 1.27)
					(thickness 0.15)
				)
				(justify left bottom)
				(hide yes)
			)
		)
		(property "Footprint" "antmicro-footprints:R_0402_1005Metric"
			(at 205.74 229.87 0)
			(effects
				(font
					(size 1.27 1.27)
					(thickness 0.15)
				)
				(justify left bottom)
				(hide yes)
			)
		)
		(property "Datasheet" "https://industrial.panasonic.com/cdbs/www-data/pdf/RDA0000/AOA0000C301.pdf"
			(at 208.28 229.87 0)
			(effects
				(font
					(size 1.27 1.27)
					(thickness 0.15)
				)
				(justify left bottom)
				(hide yes)
			)
		)
		(property "Description" ""
			(at 190.5 250.19 0)
			(effects
				(font
					(size 1.27 1.27)
				)
			)
		)
		(property "Manufacturer" "Panasonic"
			(at 213.36 229.87 0)
			(effects
				(font
					(size 1.27 1.27)
					(thickness 0.15)
				)
				(justify left bottom)
				(hide yes)
			)
		)
		(property "MPN" "ERJ2GE0R00X"
			(at 210.82 229.87 0)
			(effects
				(font
					(size 1.27 1.27)
					(thickness 0.15)
				)
				(justify left bottom)
				(hide yes)
			)
		)
		(property "Val" "0R"
			(at 193.04 248.92 90)
			(effects
				(font
					(size 1.27 1.27)
					(thickness 0.15)
				)
				(justify right)
			)
		)
		(property "DNP" "DNP"
			(at 190.5 245.745 0)
			(effects
				(font
					(size 1.27 1.27)
				)
				(justify right)
			)
		)
		(property "License" "Apache-2.0"
			(at 215.9 229.87 0)
			(effects
				(font
					(size 1.27 1.27)
					(thickness 0.15)
				)
				(justify left bottom)
				(hide yes)
			)
		)
		(property "Author" "Antmicro"
			(at 218.44 229.87 0)
			(effects
				(font
					(size 1.27 1.27)
					(thickness 0.15)
				)
				(justify left bottom)
				(hide yes)
			)
		)
		(property "Tolerance" "~"
			(at 200.66 229.87 0)
			(effects
				(font
					(size 1.27 1.27)
				)
				(justify left bottom)
				(hide yes)
			)
		)
		(property "Current" "1A"
			(at 193.04 251.4599 90)
			(effects
				(font
					(size 1.27 1.27)
					(thickness 0.15)
				)
				(justify right)
				(hide yes)
			)
		)
		(pin "1"
		)
		(pin "2"
		)
		(instances
			(project "k410t-devboard"
				(path ""
					(reference "R303")
					(unit 1)
				)
			)
		)
	)
	(symbol
		(lib_id "antmicropower:GND")
		(at 374.65 226.06 0)
		(unit 1)
		(exclude_from_sim no)
		(in_bom yes)
		(on_board yes)
		(dnp no)
		(fields_autoplaced yes)
		(property "Reference" "#PWR0450"
			(at 374.65 232.41 0)
			(effects
				(font
					(size 1.27 1.27)
				)
				(hide yes)
			)
		)
		(property "Value" "GND"
			(at 374.65 229.87 0)
			(effects
				(font
					(size 1.27 1.27)
				)
			)
		)
		(property "Footprint" ""
			(at 383.54 233.68 0)
			(effects
				(font
					(size 1.27 1.27)
					(thickness 0.15)
				)
				(justify left bottom)
				(hide yes)
			)
		)
		(property "Datasheet" ""
			(at 383.54 238.76 0)
			(effects
				(font
					(size 1.27 1.27)
					(thickness 0.15)
				)
				(justify left bottom)
				(hide yes)
			)
		)
		(property "Description" ""
			(at 374.65 226.06 0)
			(effects
				(font
					(size 1.27 1.27)
				)
			)
		)
		(property "Author" "Antmicro"
			(at 383.54 233.68 0)
			(effects
				(font
					(size 1.27 1.27)
					(thickness 0.15)
				)
				(justify left bottom)
				(hide yes)
			)
		)
		(property "License" "Apache-2.0"
			(at 383.54 236.22 0)
			(effects
				(font
					(size 1.27 1.27)
					(thickness 0.15)
				)
				(justify left bottom)
				(hide yes)
			)
		)
		(pin "1"
		)
		(instances
			(project "k410t-devboard"
				(path ""
					(reference "#PWR0450")
					(unit 1)
				)
			)
		)
	)
	(symbol
		(lib_id "antmicroResistors0402:R_0R_0402")
		(at 146.05 46.99 270)
		(unit 1)
		(exclude_from_sim no)
		(in_bom no)
		(on_board yes)
		(dnp yes)
		(property "Reference" "R364"
			(at 147.32 48.26 90)
			(effects
				(font
					(size 1.27 1.27)
				)
				(justify left)
			)
		)
		(property "Value" "R_0R_0402"
			(at 133.35 67.31 0)
			(effects
				(font
					(size 1.27 1.27)
					(thickness 0.15)
				)
				(justify left bottom)
				(hide yes)
			)
		)
		(property "Footprint" "antmicro-footprints:R_0402_1005Metric"
			(at 130.81 67.31 0)
			(effects
				(font
					(size 1.27 1.27)
					(thickness 0.15)
				)
				(justify left bottom)
				(hide yes)
			)
		)
		(property "Datasheet" "https://industrial.panasonic.com/cdbs/www-data/pdf/RDA0000/AOA0000C301.pdf"
			(at 128.27 67.31 0)
			(effects
				(font
					(size 1.27 1.27)
					(thickness 0.15)
				)
				(justify left bottom)
				(hide yes)
			)
		)
		(property "Description" ""
			(at 146.05 46.99 0)
			(effects
				(font
					(size 1.27 1.27)
				)
			)
		)
		(property "Manufacturer" "Panasonic"
			(at 123.19 67.31 0)
			(effects
				(font
					(size 1.27 1.27)
					(thickness 0.15)
				)
				(justify left bottom)
				(hide yes)
			)
		)
		(property "MPN" "ERJ2GE0R00X"
			(at 125.73 67.31 0)
			(effects
				(font
					(size 1.27 1.27)
					(thickness 0.15)
				)
				(justify left bottom)
				(hide yes)
			)
		)
		(property "Val" "0R"
			(at 147.32 50.8 90)
			(effects
				(font
					(size 1.27 1.27)
					(thickness 0.15)
				)
				(justify left)
			)
		)
		(property "DNP" "DNP"
			(at 146.05 49.53 0)
			(effects
				(font
					(size 1.27 1.27)
				)
			)
		)
		(property "License" "Apache-2.0"
			(at 120.65 67.31 0)
			(effects
				(font
					(size 1.27 1.27)
					(thickness 0.15)
				)
				(justify left bottom)
				(hide yes)
			)
		)
		(property "Author" "Antmicro"
			(at 118.11 67.31 0)
			(effects
				(font
					(size 1.27 1.27)
					(thickness 0.15)
				)
				(justify left bottom)
				(hide yes)
			)
		)
		(property "Tolerance" "~"
			(at 135.89 67.31 0)
			(effects
				(font
					(size 1.27 1.27)
				)
				(justify left bottom)
				(hide yes)
			)
		)
		(property "Current" "1A"
			(at 142.24 49.53 0)
			(effects
				(font
					(size 1.27 1.27)
					(thickness 0.15)
				)
				(hide yes)
			)
		)
		(pin "1"
		)
		(pin "2"
		)
		(instances
			(project "k410t-devboard"
				(path ""
					(reference "R364")
					(unit 1)
				)
			)
		)
	)
	(symbol
		(lib_id "antmicroResistors0402:R_10k_0402")
		(at 302.26 237.49 90)
		(unit 1)
		(exclude_from_sim no)
		(in_bom yes)
		(on_board yes)
		(dnp no)
		(fields_autoplaced yes)
		(property "Reference" "R324"
			(at 304.165 233.6799 90)
			(effects
				(font
					(size 1.27 1.27)
				)
				(justify right)
			)
		)
		(property "Value" "R_10k_0402"
			(at 314.96 217.17 0)
			(effects
				(font
					(size 1.27 1.27)
					(thickness 0.15)
				)
				(justify left bottom)
				(hide yes)
			)
		)
		(property "Footprint" "antmicro-footprints:R_0402_1005Metric"
			(at 317.5 217.17 0)
			(effects
				(font
					(size 1.27 1.27)
					(thickness 0.15)
				)
				(justify left bottom)
				(hide yes)
			)
		)
		(property "Datasheet" "https://www.bourns.com/docs/product-datasheets/cr.pdf"
			(at 320.04 217.17 0)
			(effects
				(font
					(size 1.27 1.27)
					(thickness 0.15)
				)
				(justify left bottom)
				(hide yes)
			)
		)
		(property "Description" ""
			(at 302.26 237.49 0)
			(effects
				(font
					(size 1.27 1.27)
				)
			)
		)
		(property "Manufacturer" "Bourns"
			(at 325.12 217.17 0)
			(effects
				(font
					(size 1.27 1.27)
					(thickness 0.15)
				)
				(justify left bottom)
				(hide yes)
			)
		)
		(property "MPN" "CR0402-FX-1002GLF"
			(at 322.58 217.17 0)
			(effects
				(font
					(size 1.27 1.27)
					(thickness 0.15)
				)
				(justify left bottom)
				(hide yes)
			)
		)
		(property "Val" "10k"
			(at 304.165 236.2199 90)
			(effects
				(font
					(size 1.27 1.27)
					(thickness 0.15)
				)
				(justify right)
			)
		)
		(property "License" "Apache-2.0"
			(at 327.66 217.17 0)
			(effects
				(font
					(size 1.27 1.27)
					(thickness 0.15)
				)
				(justify left bottom)
				(hide yes)
			)
		)
		(property "Author" "Antmicro"
			(at 330.2 217.17 0)
			(effects
				(font
					(size 1.27 1.27)
					(thickness 0.15)
				)
				(justify left bottom)
				(hide yes)
			)
		)
		(property "Tolerance" "1%"
			(at 312.42 217.17 0)
			(effects
				(font
					(size 1.27 1.27)
				)
				(justify left bottom)
				(hide yes)
			)
		)
		(pin "1"
		)
		(pin "2"
		)
		(instances
			(project "k410t-devboard"
				(path ""
					(reference "R324")
					(unit 1)
				)
			)
		)
	)
	(symbol
		(lib_id "antmicroResistors0402:R_100k_0402")
		(at 351.79 208.28 90)
		(unit 1)
		(exclude_from_sim no)
		(in_bom yes)
		(on_board yes)
		(dnp no)
		(fields_autoplaced yes)
		(property "Reference" "R341"
			(at 354.33 204.4699 90)
			(effects
				(font
					(size 1.27 1.27)
				)
				(justify right)
			)
		)
		(property "Value" "R_100k_0402"
			(at 364.49 187.96 0)
			(effects
				(font
					(size 1.27 1.27)
					(thickness 0.15)
				)
				(justify left bottom)
				(hide yes)
			)
		)
		(property "Footprint" "antmicro-footprints:R_0402_1005Metric"
			(at 367.03 187.96 0)
			(effects
				(font
					(size 1.27 1.27)
					(thickness 0.15)
				)
				(justify left bottom)
				(hide yes)
			)
		)
		(property "Datasheet" "https://www.bourns.com/docs/product-datasheets/cr.pdf"
			(at 369.57 187.96 0)
			(effects
				(font
					(size 1.27 1.27)
					(thickness 0.15)
				)
				(justify left bottom)
				(hide yes)
			)
		)
		(property "Description" ""
			(at 351.79 208.28 0)
			(effects
				(font
					(size 1.27 1.27)
				)
			)
		)
		(property "Manufacturer" "Bourns"
			(at 374.65 187.96 0)
			(effects
				(font
					(size 1.27 1.27)
					(thickness 0.15)
				)
				(justify left bottom)
				(hide yes)
			)
		)
		(property "MPN" "CR0402-FX-1003GLF"
			(at 372.11 187.96 0)
			(effects
				(font
					(size 1.27 1.27)
					(thickness 0.15)
				)
				(justify left bottom)
				(hide yes)
			)
		)
		(property "Val" "100k"
			(at 354.33 207.0099 90)
			(effects
				(font
					(size 1.27 1.27)
					(thickness 0.15)
				)
				(justify right)
			)
		)
		(property "License" "Apache-2.0"
			(at 377.19 187.96 0)
			(effects
				(font
					(size 1.27 1.27)
					(thickness 0.15)
				)
				(justify left bottom)
				(hide yes)
			)
		)
		(property "Author" "Antmicro"
			(at 379.73 187.96 0)
			(effects
				(font
					(size 1.27 1.27)
					(thickness 0.15)
				)
				(justify left bottom)
				(hide yes)
			)
		)
		(property "Tolerance" "1%"
			(at 361.95 187.96 0)
			(effects
				(font
					(size 1.27 1.27)
				)
				(justify left bottom)
				(hide yes)
			)
		)
		(pin "1"
		)
		(pin "2"
		)
		(instances
			(project "k410t-devboard"
				(path ""
					(reference "R341")
					(unit 1)
				)
			)
		)
	)
	(symbol
		(lib_id "antmicropower:+5V")
		(at 256.54 181.61 0)
		(unit 1)
		(exclude_from_sim no)
		(in_bom yes)
		(on_board yes)
		(dnp no)
		(fields_autoplaced yes)
		(property "Reference" "#PWR0380"
			(at 256.54 185.42 0)
			(effects
				(font
					(size 1.27 1.27)
				)
				(hide yes)
			)
		)
		(property "Value" "+5V"
			(at 256.54 178.054 0)
			(effects
				(font
					(size 1.27 1.27)
				)
			)
		)
		(property "Footprint" ""
			(at 256.54 181.61 0)
			(effects
				(font
					(size 1.27 1.27)
				)
				(hide yes)
			)
		)
		(property "Datasheet" ""
			(at 256.54 181.61 0)
			(effects
				(font
					(size 1.27 1.27)
				)
				(hide yes)
			)
		)
		(property "Description" ""
			(at 256.54 181.61 0)
			(effects
				(font
					(size 1.27 1.27)
				)
			)
		)
		(property "Author" "Antmicro"
			(at 271.78 189.23 0)
			(effects
				(font
					(size 1.27 1.27)
					(thickness 0.15)
				)
				(justify left bottom)
				(hide yes)
			)
		)
		(property "License" "Apache-2.0"
			(at 271.78 191.77 0)
			(effects
				(font
					(size 1.27 1.27)
					(thickness 0.15)
				)
				(justify left bottom)
				(hide yes)
			)
		)
		(pin "1"
		)
		(instances
			(project "k410t-devboard"
				(path ""
					(reference "#PWR0380")
					(unit 1)
				)
			)
		)
	)
	(symbol
		(lib_id "antmicropower:GND")
		(at 186.69 124.46 0)
		(unit 1)
		(exclude_from_sim no)
		(in_bom yes)
		(on_board yes)
		(dnp no)
		(property "Reference" "#PWR0395"
			(at 186.69 130.81 0)
			(effects
				(font
					(size 1.27 1.27)
				)
				(hide yes)
			)
		)
		(property "Value" "GND"
			(at 186.69 128.27 0)
			(effects
				(font
					(size 1.27 1.27)
				)
			)
		)
		(property "Footprint" ""
			(at 195.58 132.08 0)
			(effects
				(font
					(size 1.27 1.27)
					(thickness 0.15)
				)
				(justify left bottom)
				(hide yes)
			)
		)
		(property "Datasheet" ""
			(at 195.58 137.16 0)
			(effects
				(font
					(size 1.27 1.27)
					(thickness 0.15)
				)
				(justify left bottom)
				(hide yes)
			)
		)
		(property "Description" ""
			(at 186.69 124.46 0)
			(effects
				(font
					(size 1.27 1.27)
				)
			)
		)
		(property "Author" "Antmicro"
			(at 195.58 132.08 0)
			(effects
				(font
					(size 1.27 1.27)
					(thickness 0.15)
				)
				(justify left bottom)
				(hide yes)
			)
		)
		(property "License" "Apache-2.0"
			(at 195.58 134.62 0)
			(effects
				(font
					(size 1.27 1.27)
					(thickness 0.15)
				)
				(justify left bottom)
				(hide yes)
			)
		)
		(pin "1"
		)
		(instances
			(project "k410t-devboard"
				(path ""
					(reference "#PWR0395")
					(unit 1)
				)
			)
		)
	)
	(symbol
		(lib_id "k410t-devboard:Net-Tie_2")
		(at 204.47 229.87 90)
		(unit 1)
		(exclude_from_sim no)
		(in_bom yes)
		(on_board yes)
		(dnp no)
		(fields_autoplaced yes)
		(property "Reference" "NT32"
			(at 203.2 229.87 0)
			(effects
				(font
					(size 1.27 1.27)
				)
				(hide yes)
			)
		)
		(property "Value" "Net-Tie_2"
			(at 205.74 227.9649 90)
			(effects
				(font
					(size 1.27 1.27)
					(thickness 0.15)
				)
				(justify right)
				(hide yes)
			)
		)
		(property "Footprint" "antmicro-footprints:NetTie-2_SMD_Pad0.127mm"
			(at 209.55 208.28 0)
			(effects
				(font
					(size 1.27 1.27)
					(thickness 0.15)
				)
				(justify left bottom)
				(hide yes)
			)
		)
		(property "Datasheet" ""
			(at 212.09 208.28 0)
			(effects
				(font
					(size 1.27 1.27)
					(thickness 0.15)
				)
				(justify left bottom)
				(hide yes)
			)
		)
		(property "Description" ""
			(at 204.47 229.87 0)
			(effects
				(font
					(size 1.27 1.27)
				)
			)
		)
		(property "MPN" ""
			(at 213.36 208.28 0)
			(effects
				(font
					(size 1.27 1.27)
				)
				(justify left)
				(hide yes)
			)
		)
		(property "Manufacturer" ""
			(at 215.9 208.28 0)
			(effects
				(font
					(size 1.27 1.27)
				)
				(justify left)
				(hide yes)
			)
		)
		(property "Author" "Antmicro"
			(at 219.71 208.28 0)
			(effects
				(font
					(size 1.27 1.27)
					(thickness 0.15)
				)
				(justify left bottom)
				(hide yes)
			)
		)
		(property "License" "Apache-2.0"
			(at 222.25 208.28 0)
			(effects
				(font
					(size 1.27 1.27)
					(thickness 0.15)
				)
				(justify left bottom)
				(hide yes)
			)
		)
		(pin "1"
		)
		(pin "2"
		)
		(instances
			(project "k410t-devboard"
				(path ""
					(reference "NT32")
					(unit 1)
				)
			)
		)
	)
	(symbol
		(lib_id "antmicroCapacitors0402:C_100n_0402")
		(at 217.17 40.64 90)
		(unit 1)
		(exclude_from_sim no)
		(in_bom yes)
		(on_board yes)
		(dnp no)
		(fields_autoplaced yes)
		(property "Reference" "C338"
			(at 219.71 36.8235 90)
			(effects
				(font
					(size 1.27 1.27)
				)
				(justify right)
			)
		)
		(property "Value" "C_100n_0402"
			(at 227.33 20.32 0)
			(effects
				(font
					(size 1.27 1.27)
					(thickness 0.15)
				)
				(justify left bottom)
				(hide yes)
			)
		)
		(property "Footprint" "antmicro-footprints:C_0402_1005Metric"
			(at 229.87 20.32 0)
			(effects
				(font
					(size 1.27 1.27)
					(thickness 0.15)
				)
				(justify left bottom)
				(hide yes)
			)
		)
		(property "Datasheet" "https://www.murata.com/products/productdetail?partno=GRM155R61H104KE14%23"
			(at 232.41 20.32 0)
			(effects
				(font
					(size 1.27 1.27)
					(thickness 0.15)
				)
				(justify left bottom)
				(hide yes)
			)
		)
		(property "Description" ""
			(at 217.17 40.64 0)
			(effects
				(font
					(size 1.27 1.27)
				)
			)
		)
		(property "Manufacturer" "Murata"
			(at 237.49 20.32 0)
			(effects
				(font
					(size 1.27 1.27)
					(thickness 0.15)
				)
				(justify left bottom)
				(hide yes)
			)
		)
		(property "MPN" "GRM155R61H104KE14D"
			(at 234.95 20.32 0)
			(effects
				(font
					(size 1.27 1.27)
					(thickness 0.15)
				)
				(justify left bottom)
				(hide yes)
			)
		)
		(property "Val" "100n"
			(at 219.71 39.3635 90)
			(effects
				(font
					(size 1.27 1.27)
					(thickness 0.15)
				)
				(justify right)
			)
		)
		(property "License" "Apache-2.0"
			(at 240.03 20.32 0)
			(effects
				(font
					(size 1.27 1.27)
					(thickness 0.15)
				)
				(justify left bottom)
				(hide yes)
			)
		)
		(property "Author" "Antmicro"
			(at 242.57 20.32 0)
			(effects
				(font
					(size 1.27 1.27)
					(thickness 0.15)
				)
				(justify left bottom)
				(hide yes)
			)
		)
		(property "Voltage" "50V"
			(at 245.11 20.32 0)
			(effects
				(font
					(size 1.27 1.27)
				)
				(justify left bottom)
				(hide yes)
			)
		)
		(property "Dielectric" "X5R"
			(at 247.65 20.32 0)
			(effects
				(font
					(size 1.27 1.27)
				)
				(justify left bottom)
				(hide yes)
			)
		)
		(pin "1"
		)
		(pin "2"
		)
		(instances
			(project "k410t-devboard"
				(path ""
					(reference "C338")
					(unit 1)
				)
			)
		)
	)
	(symbol
		(lib_id "antmicropower:GND")
		(at 312.42 240.03 0)
		(unit 1)
		(exclude_from_sim no)
		(in_bom yes)
		(on_board yes)
		(dnp no)
		(fields_autoplaced yes)
		(property "Reference" "#PWR0419"
			(at 312.42 246.38 0)
			(effects
				(font
					(size 1.27 1.27)
				)
				(hide yes)
			)
		)
		(property "Value" "GND"
			(at 312.42 243.84 0)
			(effects
				(font
					(size 1.27 1.27)
				)
			)
		)
		(property "Footprint" ""
			(at 321.31 247.65 0)
			(effects
				(font
					(size 1.27 1.27)
					(thickness 0.15)
				)
				(justify left bottom)
				(hide yes)
			)
		)
		(property "Datasheet" ""
			(at 321.31 252.73 0)
			(effects
				(font
					(size 1.27 1.27)
					(thickness 0.15)
				)
				(justify left bottom)
				(hide yes)
			)
		)
		(property "Description" ""
			(at 312.42 240.03 0)
			(effects
				(font
					(size 1.27 1.27)
				)
			)
		)
		(property "Author" "Antmicro"
			(at 321.31 247.65 0)
			(effects
				(font
					(size 1.27 1.27)
					(thickness 0.15)
				)
				(justify left bottom)
				(hide yes)
			)
		)
		(property "License" "Apache-2.0"
			(at 321.31 250.19 0)
			(effects
				(font
					(size 1.27 1.27)
					(thickness 0.15)
				)
				(justify left bottom)
				(hide yes)
			)
		)
		(pin "1"
		)
		(instances
			(project "k410t-devboard"
				(path ""
					(reference "#PWR0419")
					(unit 1)
				)
			)
		)
	)
	(symbol
		(lib_id "antmicropower:+1V35")
		(at 256.54 219.71 0)
		(unit 1)
		(exclude_from_sim no)
		(in_bom yes)
		(on_board yes)
		(dnp no)
		(fields_autoplaced yes)
		(property "Reference" "#PWR0432"
			(at 256.54 223.52 0)
			(effects
				(font
					(size 1.27 1.27)
				)
				(hide yes)
			)
		)
		(property "Value" "+1V35"
			(at 256.54 216.154 0)
			(effects
				(font
					(size 1.27 1.27)
				)
			)
		)
		(property "Footprint" ""
			(at 256.54 219.71 0)
			(effects
				(font
					(size 1.27 1.27)
				)
				(hide yes)
			)
		)
		(property "Datasheet" ""
			(at 256.54 219.71 0)
			(effects
				(font
					(size 1.27 1.27)
				)
				(hide yes)
			)
		)
		(property "Description" ""
			(at 256.54 219.71 0)
			(effects
				(font
					(size 1.27 1.27)
				)
			)
		)
		(pin "1"
		)
		(instances
			(project "k410t-devboard"
				(path ""
					(reference "#PWR0432")
					(unit 1)
				)
			)
		)
	)
	(symbol
		(lib_id "antmicropower:GND")
		(at 238.76 124.46 0)
		(unit 1)
		(exclude_from_sim no)
		(in_bom yes)
		(on_board yes)
		(dnp no)
		(property "Reference" "#PWR0403"
			(at 238.76 130.81 0)
			(effects
				(font
					(size 1.27 1.27)
				)
				(hide yes)
			)
		)
		(property "Value" "GND"
			(at 238.76 128.27 0)
			(effects
				(font
					(size 1.27 1.27)
				)
			)
		)
		(property "Footprint" ""
			(at 247.65 132.08 0)
			(effects
				(font
					(size 1.27 1.27)
					(thickness 0.15)
				)
				(justify left bottom)
				(hide yes)
			)
		)
		(property "Datasheet" ""
			(at 247.65 137.16 0)
			(effects
				(font
					(size 1.27 1.27)
					(thickness 0.15)
				)
				(justify left bottom)
				(hide yes)
			)
		)
		(property "Description" ""
			(at 238.76 124.46 0)
			(effects
				(font
					(size 1.27 1.27)
				)
			)
		)
		(property "Author" "Antmicro"
			(at 247.65 132.08 0)
			(effects
				(font
					(size 1.27 1.27)
					(thickness 0.15)
				)
				(justify left bottom)
				(hide yes)
			)
		)
		(property "License" "Apache-2.0"
			(at 247.65 134.62 0)
			(effects
				(font
					(size 1.27 1.27)
					(thickness 0.15)
				)
				(justify left bottom)
				(hide yes)
			)
		)
		(pin "1"
		)
		(instances
			(project "k410t-devboard"
				(path ""
					(reference "#PWR0403")
					(unit 1)
				)
			)
		)
	)
	(symbol
		(lib_id "antmicroDiodesZenerSingle:BZX84C5V1-TP")
		(at 142.24 71.12 90)
		(unit 1)
		(exclude_from_sim no)
		(in_bom yes)
		(on_board yes)
		(dnp no)
		(property "Reference" "D33"
			(at 140.335 66.675 90)
			(effects
				(font
					(size 1.27 1.27)
				)
				(justify left)
			)
		)
		(property "Value" "BZX84C5V1-TP"
			(at 141.605 63.5 90)
			(effects
				(font
					(size 1.27 1.27)
					(thickness 0.15)
				)
				(justify left bottom)
			)
		)
		(property "Footprint" "antmicro-footprints:SOT-23-3"
			(at 152.4 48.26 0)
			(effects
				(font
					(size 1.27 1.27)
					(thickness 0.15)
				)
				(justify left bottom)
				(hide yes)
			)
		)
		(property "Datasheet" "https://www.mccsemi.com/pdf/Products/BZX84C(B)2V4~BZX84C(B)75(SOT-23).pdf"
			(at 154.94 48.26 0)
			(effects
				(font
					(size 1.27 1.27)
					(thickness 0.15)
				)
				(justify left bottom)
				(hide yes)
			)
		)
		(property "Description" ""
			(at 142.24 71.12 0)
			(effects
				(font
					(size 1.27 1.27)
				)
			)
		)
		(property "MPN" "BZX84C5V1-TP"
			(at 157.48 48.26 0)
			(effects
				(font
					(size 1.27 1.27)
					(thickness 0.15)
				)
				(justify left bottom)
				(hide yes)
			)
		)
		(property "Manufacturer" "Micro Commercial Components"
			(at 160.02 48.26 0)
			(effects
				(font
					(size 1.27 1.27)
					(thickness 0.15)
				)
				(justify left bottom)
				(hide yes)
			)
		)
		(property "Author" "Antmicro"
			(at 162.56 48.26 0)
			(effects
				(font
					(size 1.27 1.27)
					(thickness 0.15)
				)
				(justify left bottom)
				(hide yes)
			)
		)
		(property "License" "Apache-2.0"
			(at 165.1 48.26 0)
			(effects
				(font
					(size 1.27 1.27)
					(thickness 0.15)
				)
				(justify left bottom)
				(hide yes)
			)
		)
		(pin "1"
		)
		(pin "2"
		)
		(pin "3"
		)
		(instances
			(project "k410t-devboard"
				(path ""
					(reference "D33")
					(unit 1)
				)
			)
		)
	)
	(symbol
		(lib_id "antmicropower:+1V8")
		(at 135.89 114.3 0)
		(unit 1)
		(exclude_from_sim no)
		(in_bom yes)
		(on_board yes)
		(dnp no)
		(property "Reference" "#PWR0351"
			(at 135.89 118.11 0)
			(effects
				(font
					(size 1.27 1.27)
				)
				(hide yes)
			)
		)
		(property "Value" "+1V8"
			(at 135.89 110.744 0)
			(effects
				(font
					(size 1.27 1.27)
				)
			)
		)
		(property "Footprint" ""
			(at 151.13 121.92 0)
			(effects
				(font
					(size 1.27 1.27)
					(thickness 0.15)
				)
				(justify left bottom)
				(hide yes)
			)
		)
		(property "Datasheet" ""
			(at 151.13 124.46 0)
			(effects
				(font
					(size 1.27 1.27)
					(thickness 0.15)
				)
				(justify left bottom)
				(hide yes)
			)
		)
		(property "Description" ""
			(at 135.89 114.3 0)
			(effects
				(font
					(size 1.27 1.27)
				)
			)
		)
		(property "Author" "Antmicro"
			(at 151.13 121.92 0)
			(effects
				(font
					(size 1.27 1.27)
					(thickness 0.15)
				)
				(justify left bottom)
				(hide yes)
			)
		)
		(property "License" "Apache-2.0"
			(at 151.13 124.46 0)
			(effects
				(font
					(size 1.27 1.27)
					(thickness 0.15)
				)
				(justify left bottom)
				(hide yes)
			)
		)
		(pin "1"
		)
		(instances
			(project "k410t-devboard"
				(path ""
					(reference "#PWR0351")
					(unit 1)
				)
			)
		)
	)
	(symbol
		(lib_id "antmicroResistors0603:R_0R_22.4A_0603")
		(at 124.46 222.25 0)
		(unit 1)
		(exclude_from_sim no)
		(in_bom yes)
		(on_board yes)
		(dnp no)
		(property "Reference" "R291"
			(at 127 214.63 0)
			(effects
				(font
					(size 1.27 1.27)
				)
			)
		)
		(property "Value" "R_0R_22.4A_0603"
			(at 147.32 229.87 0)
			(effects
				(font
					(size 1.27 1.27)
					(thickness 0.15)
				)
				(justify left bottom)
				(hide yes)
			)
		)
		(property "Footprint" "antmicro-footprints:R_0603_1608Metric"
			(at 147.32 234.95 0)
			(effects
				(font
					(size 1.27 1.27)
					(thickness 0.15)
				)
				(justify left bottom)
				(hide yes)
			)
		)
		(property "Datasheet" "https://fscdn.rohm.com/en/products/databook/datasheet/passive/resistor/chip_resistor/pmr-jpw-e.pdf"
			(at 147.32 237.49 0)
			(effects
				(font
					(size 1.27 1.27)
					(thickness 0.15)
				)
				(justify left bottom)
				(hide yes)
			)
		)
		(property "Description" ""
			(at 124.46 222.25 0)
			(effects
				(font
					(size 1.27 1.27)
				)
			)
		)
		(property "Manufacturer" "ROHM Semiconductor"
			(at 147.32 240.03 0)
			(effects
				(font
					(size 1.27 1.27)
					(thickness 0.15)
				)
				(justify left bottom)
				(hide yes)
			)
		)
		(property "MPN" "PMR03EZPJ000"
			(at 147.32 242.57 0)
			(effects
				(font
					(size 1.27 1.27)
					(thickness 0.15)
				)
				(justify left bottom)
				(hide yes)
			)
		)
		(property "Val" "0R"
			(at 127 217.17 0)
			(effects
				(font
					(size 1.27 1.27)
					(thickness 0.15)
				)
			)
		)
		(property "Author" "Antmicro"
			(at 147.32 245.11 0)
			(effects
				(font
					(size 1.27 1.27)
					(thickness 0.15)
				)
				(justify left bottom)
				(hide yes)
			)
		)
		(property "License" "Apache-2.0"
			(at 147.32 247.65 0)
			(effects
				(font
					(size 1.27 1.27)
					(thickness 0.15)
				)
				(justify left bottom)
				(hide yes)
			)
		)
		(property "Max. Curr." "22.4A"
			(at 127 219.71 0)
			(effects
				(font
					(size 1.27 1.27)
					(thickness 0.15)
				)
			)
		)
		(property "Tolerance" "template_tolerance"
			(at 144.78 232.41 0)
			(effects
				(font
					(size 1.27 1.27)
				)
				(justify left bottom)
				(hide yes)
			)
		)
		(pin "1"
		)
		(pin "2"
		)
		(instances
			(project "k410t-devboard"
				(path ""
					(reference "R291")
					(unit 1)
				)
			)
		)
	)
	(symbol
		(lib_id "antmicropower:+3.3V")
		(at 351.79 199.39 0)
		(unit 1)
		(exclude_from_sim no)
		(in_bom yes)
		(on_board yes)
		(dnp no)
		(fields_autoplaced yes)
		(property "Reference" "#PWR0460"
			(at 351.79 203.2 0)
			(effects
				(font
					(size 1.27 1.27)
				)
				(hide yes)
			)
		)
		(property "Value" "+3V3"
			(at 351.79 195.834 0)
			(effects
				(font
					(size 1.27 1.27)
				)
			)
		)
		(property "Footprint" ""
			(at 351.79 199.39 0)
			(effects
				(font
					(size 1.27 1.27)
				)
				(hide yes)
			)
		)
		(property "Datasheet" ""
			(at 351.79 199.39 0)
			(effects
				(font
					(size 1.27 1.27)
				)
				(hide yes)
			)
		)
		(property "Description" ""
			(at 351.79 199.39 0)
			(effects
				(font
					(size 1.27 1.27)
				)
			)
		)
		(pin "1"
		)
		(instances
			(project "k410t-devboard"
				(path ""
					(reference "#PWR0460")
					(unit 1)
				)
			)
		)
	)
	(symbol
		(lib_id "antmicroResistors0402:R_47k_0402")
		(at 255.27 44.45 90)
		(unit 1)
		(exclude_from_sim no)
		(in_bom yes)
		(on_board yes)
		(dnp no)
		(property "Reference" "R321"
			(at 256.54 40.64 90)
			(effects
				(font
					(size 1.27 1.27)
				)
				(justify right)
			)
		)
		(property "Value" "R_47k_0402"
			(at 267.97 24.13 0)
			(effects
				(font
					(size 1.27 1.27)
					(thickness 0.15)
				)
				(justify left bottom)
				(hide yes)
			)
		)
		(property "Footprint" "antmicro-footprints:R_0402_1005Metric"
			(at 270.51 24.13 0)
			(effects
				(font
					(size 1.27 1.27)
					(thickness 0.15)
				)
				(justify left bottom)
				(hide yes)
			)
		)
		(property "Datasheet" "https://www.bourns.com/docs/product-datasheets/cr.pdf"
			(at 273.05 24.13 0)
			(effects
				(font
					(size 1.27 1.27)
					(thickness 0.15)
				)
				(justify left bottom)
				(hide yes)
			)
		)
		(property "Description" ""
			(at 255.27 44.45 0)
			(effects
				(font
					(size 1.27 1.27)
				)
			)
		)
		(property "Manufacturer" "Bourns"
			(at 278.13 24.13 0)
			(effects
				(font
					(size 1.27 1.27)
					(thickness 0.15)
				)
				(justify left bottom)
				(hide yes)
			)
		)
		(property "MPN" "CR0402-FX-4702GLF"
			(at 275.59 24.13 0)
			(effects
				(font
					(size 1.27 1.27)
					(thickness 0.15)
				)
				(justify left bottom)
				(hide yes)
			)
		)
		(property "Val" "47k"
			(at 256.54 43.18 90)
			(effects
				(font
					(size 1.27 1.27)
					(thickness 0.15)
				)
				(justify right)
			)
		)
		(property "License" "Apache-2.0"
			(at 280.67 24.13 0)
			(effects
				(font
					(size 1.27 1.27)
					(thickness 0.15)
				)
				(justify left bottom)
				(hide yes)
			)
		)
		(property "Author" "Antmicro"
			(at 283.21 24.13 0)
			(effects
				(font
					(size 1.27 1.27)
					(thickness 0.15)
				)
				(justify left bottom)
				(hide yes)
			)
		)
		(property "Tolerance" "1%"
			(at 265.43 24.13 0)
			(effects
				(font
					(size 1.27 1.27)
				)
				(justify left bottom)
				(hide yes)
			)
		)
		(pin "1"
		)
		(pin "2"
		)
		(instances
			(project "k410t-devboard"
				(path ""
					(reference "R321")
					(unit 1)
				)
			)
		)
	)
	(symbol
		(lib_id "antmicropower:GND")
		(at 312.42 205.74 0)
		(unit 1)
		(exclude_from_sim no)
		(in_bom yes)
		(on_board yes)
		(dnp no)
		(property "Reference" "#PWR0417"
			(at 312.42 212.09 0)
			(effects
				(font
					(size 1.27 1.27)
				)
				(hide yes)
			)
		)
		(property "Value" "GND"
			(at 312.42 209.55 0)
			(effects
				(font
					(size 1.27 1.27)
				)
			)
		)
		(property "Footprint" ""
			(at 321.31 213.36 0)
			(effects
				(font
					(size 1.27 1.27)
					(thickness 0.15)
				)
				(justify left bottom)
				(hide yes)
			)
		)
		(property "Datasheet" ""
			(at 321.31 218.44 0)
			(effects
				(font
					(size 1.27 1.27)
					(thickness 0.15)
				)
				(justify left bottom)
				(hide yes)
			)
		)
		(property "Description" ""
			(at 312.42 205.74 0)
			(effects
				(font
					(size 1.27 1.27)
				)
			)
		)
		(property "Author" "Antmicro"
			(at 321.31 213.36 0)
			(effects
				(font
					(size 1.27 1.27)
					(thickness 0.15)
				)
				(justify left bottom)
				(hide yes)
			)
		)
		(property "License" "Apache-2.0"
			(at 321.31 215.9 0)
			(effects
				(font
					(size 1.27 1.27)
					(thickness 0.15)
				)
				(justify left bottom)
				(hide yes)
			)
		)
		(pin "1"
		)
		(instances
			(project "k410t-devboard"
				(path ""
					(reference "#PWR0417")
					(unit 1)
				)
			)
		)
	)
	(symbol
		(lib_id "antmicropower:+1V2")
		(at 137.16 132.08 0)
		(unit 1)
		(exclude_from_sim no)
		(in_bom yes)
		(on_board yes)
		(dnp no)
		(property "Reference" "#PWR0352"
			(at 137.16 135.89 0)
			(effects
				(font
					(size 1.27 1.27)
				)
				(hide yes)
			)
		)
		(property "Value" "+1V2"
			(at 137.16 128.524 0)
			(effects
				(font
					(size 1.27 1.27)
				)
			)
		)
		(property "Footprint" ""
			(at 137.16 132.08 0)
			(effects
				(font
					(size 1.27 1.27)
				)
				(hide yes)
			)
		)
		(property "Datasheet" ""
			(at 137.16 132.08 0)
			(effects
				(font
					(size 1.27 1.27)
				)
				(hide yes)
			)
		)
		(property "Description" ""
			(at 137.16 132.08 0)
			(effects
				(font
					(size 1.27 1.27)
				)
			)
		)
		(pin "1"
		)
		(instances
			(project "k410t-devboard"
				(path ""
					(reference "#PWR0352")
					(unit 1)
				)
			)
		)
	)
	(symbol
		(lib_id "antmicroResistors0402:R_0R_0402")
		(at 186.69 102.87 90)
		(unit 1)
		(exclude_from_sim no)
		(in_bom yes)
		(on_board yes)
		(dnp no)
		(fields_autoplaced yes)
		(property "Reference" "R296"
			(at 189.23 99.0599 90)
			(effects
				(font
					(size 1.27 1.27)
				)
				(justify right)
			)
		)
		(property "Value" "R_0R_0402"
			(at 199.39 82.55 0)
			(effects
				(font
					(size 1.27 1.27)
					(thickness 0.15)
				)
				(justify left bottom)
				(hide yes)
			)
		)
		(property "Footprint" "antmicro-footprints:R_0402_1005Metric"
			(at 201.93 82.55 0)
			(effects
				(font
					(size 1.27 1.27)
					(thickness 0.15)
				)
				(justify left bottom)
				(hide yes)
			)
		)
		(property "Datasheet" "https://industrial.panasonic.com/cdbs/www-data/pdf/RDA0000/AOA0000C301.pdf"
			(at 204.47 82.55 0)
			(effects
				(font
					(size 1.27 1.27)
					(thickness 0.15)
				)
				(justify left bottom)
				(hide yes)
			)
		)
		(property "Description" ""
			(at 186.69 102.87 0)
			(effects
				(font
					(size 1.27 1.27)
				)
			)
		)
		(property "Manufacturer" "Panasonic"
			(at 209.55 82.55 0)
			(effects
				(font
					(size 1.27 1.27)
					(thickness 0.15)
				)
				(justify left bottom)
				(hide yes)
			)
		)
		(property "MPN" "ERJ2GE0R00X"
			(at 207.01 82.55 0)
			(effects
				(font
					(size 1.27 1.27)
					(thickness 0.15)
				)
				(justify left bottom)
				(hide yes)
			)
		)
		(property "Val" "0R"
			(at 189.23 101.5999 90)
			(effects
				(font
					(size 1.27 1.27)
					(thickness 0.15)
				)
				(justify right)
			)
		)
		(property "License" "Apache-2.0"
			(at 212.09 82.55 0)
			(effects
				(font
					(size 1.27 1.27)
					(thickness 0.15)
				)
				(justify left bottom)
				(hide yes)
			)
		)
		(property "Author" "Antmicro"
			(at 214.63 82.55 0)
			(effects
				(font
					(size 1.27 1.27)
					(thickness 0.15)
				)
				(justify left bottom)
				(hide yes)
			)
		)
		(property "Tolerance" "~"
			(at 196.85 82.55 0)
			(effects
				(font
					(size 1.27 1.27)
				)
				(justify left bottom)
				(hide yes)
			)
		)
		(property "Current" "1A"
			(at 189.23 102.8699 90)
			(effects
				(font
					(size 1.27 1.27)
					(thickness 0.15)
				)
				(justify right)
				(hide yes)
			)
		)
		(pin "1"
		)
		(pin "2"
		)
		(instances
			(project "k410t-devboard"
				(path ""
					(reference "R296")
					(unit 1)
				)
			)
		)
	)
	(symbol
		(lib_id "antmicroResistors0603:R_0R_22.4A_0603")
		(at 124.46 115.57 0)
		(unit 1)
		(exclude_from_sim no)
		(in_bom yes)
		(on_board yes)
		(dnp no)
		(property "Reference" "R286"
			(at 127 107.95 0)
			(effects
				(font
					(size 1.27 1.27)
				)
			)
		)
		(property "Value" "R_0R_22.4A_0603"
			(at 127 109.22 0)
			(effects
				(font
					(size 1.27 1.27)
					(thickness 0.15)
				)
				(hide yes)
			)
		)
		(property "Footprint" "antmicro-footprints:R_0603_1608Metric"
			(at 147.32 128.27 0)
			(effects
				(font
					(size 1.27 1.27)
					(thickness 0.15)
				)
				(justify left bottom)
				(hide yes)
			)
		)
		(property "Datasheet" "https://fscdn.rohm.com/en/products/databook/datasheet/passive/resistor/chip_resistor/pmr-jpw-e.pdf"
			(at 147.32 130.81 0)
			(effects
				(font
					(size 1.27 1.27)
					(thickness 0.15)
				)
				(justify left bottom)
				(hide yes)
			)
		)
		(property "Description" ""
			(at 124.46 115.57 0)
			(effects
				(font
					(size 1.27 1.27)
				)
			)
		)
		(property "Manufacturer" "ROHM Semiconductor"
			(at 147.32 133.35 0)
			(effects
				(font
					(size 1.27 1.27)
					(thickness 0.15)
				)
				(justify left bottom)
				(hide yes)
			)
		)
		(property "MPN" "PMR03EZPJ000"
			(at 147.32 135.89 0)
			(effects
				(font
					(size 1.27 1.27)
					(thickness 0.15)
				)
				(justify left bottom)
				(hide yes)
			)
		)
		(property "Val" "0R"
			(at 127 110.49 0)
			(effects
				(font
					(size 1.27 1.27)
					(thickness 0.15)
				)
			)
		)
		(property "Author" "Antmicro"
			(at 147.32 138.43 0)
			(effects
				(font
					(size 1.27 1.27)
					(thickness 0.15)
				)
				(justify left bottom)
				(hide yes)
			)
		)
		(property "License" "Apache-2.0"
			(at 147.32 140.97 0)
			(effects
				(font
					(size 1.27 1.27)
					(thickness 0.15)
				)
				(justify left bottom)
				(hide yes)
			)
		)
		(property "Max. Curr." "22.4A"
			(at 127 113.03 0)
			(effects
				(font
					(size 1.27 1.27)
					(thickness 0.15)
				)
			)
		)
		(property "Tolerance" "template_tolerance"
			(at 144.78 125.73 0)
			(effects
				(font
					(size 1.27 1.27)
				)
				(justify left bottom)
				(hide yes)
			)
		)
		(pin "1"
		)
		(pin "2"
		)
		(instances
			(project "k410t-devboard"
				(path ""
					(reference "R286")
					(unit 1)
				)
			)
		)
	)
	(symbol
		(lib_id "antmicroCapacitors0402:C_100n_0402")
		(at 306.07 36.83 90)
		(unit 1)
		(exclude_from_sim no)
		(in_bom yes)
		(on_board yes)
		(dnp no)
		(fields_autoplaced yes)
		(property "Reference" "C347"
			(at 308.61 33.0136 90)
			(effects
				(font
					(size 1.27 1.27)
				)
				(justify right)
			)
		)
		(property "Value" "C_100n_0402"
			(at 316.23 16.51 0)
			(effects
				(font
					(size 1.27 1.27)
					(thickness 0.15)
				)
				(justify left bottom)
				(hide yes)
			)
		)
		(property "Footprint" "antmicro-footprints:C_0402_1005Metric"
			(at 318.77 16.51 0)
			(effects
				(font
					(size 1.27 1.27)
					(thickness 0.15)
				)
				(justify left bottom)
				(hide yes)
			)
		)
		(property "Datasheet" "https://www.murata.com/products/productdetail?partno=GRM155R61H104KE14%23"
			(at 321.31 16.51 0)
			(effects
				(font
					(size 1.27 1.27)
					(thickness 0.15)
				)
				(justify left bottom)
				(hide yes)
			)
		)
		(property "Description" ""
			(at 306.07 36.83 0)
			(effects
				(font
					(size 1.27 1.27)
				)
			)
		)
		(property "Manufacturer" "Murata"
			(at 326.39 16.51 0)
			(effects
				(font
					(size 1.27 1.27)
					(thickness 0.15)
				)
				(justify left bottom)
				(hide yes)
			)
		)
		(property "MPN" "GRM155R61H104KE14D"
			(at 323.85 16.51 0)
			(effects
				(font
					(size 1.27 1.27)
					(thickness 0.15)
				)
				(justify left bottom)
				(hide yes)
			)
		)
		(property "Val" "100n"
			(at 308.61 35.5536 90)
			(effects
				(font
					(size 1.27 1.27)
					(thickness 0.15)
				)
				(justify right)
			)
		)
		(property "License" "Apache-2.0"
			(at 328.93 16.51 0)
			(effects
				(font
					(size 1.27 1.27)
					(thickness 0.15)
				)
				(justify left bottom)
				(hide yes)
			)
		)
		(property "Author" "Antmicro"
			(at 331.47 16.51 0)
			(effects
				(font
					(size 1.27 1.27)
					(thickness 0.15)
				)
				(justify left bottom)
				(hide yes)
			)
		)
		(property "Voltage" "50V"
			(at 334.01 16.51 0)
			(effects
				(font
					(size 1.27 1.27)
				)
				(justify left bottom)
				(hide yes)
			)
		)
		(property "Dielectric" "X5R"
			(at 336.55 16.51 0)
			(effects
				(font
					(size 1.27 1.27)
				)
				(justify left bottom)
				(hide yes)
			)
		)
		(pin "1"
		)
		(pin "2"
		)
		(instances
			(project "k410t-devboard"
				(path ""
					(reference "C347")
					(unit 1)
				)
			)
		)
	)
	(symbol
		(lib_id "antmicroCapacitorsmisc:C_22u_25V_0805")
		(at 281.94 36.83 90)
		(unit 1)
		(exclude_from_sim no)
		(in_bom yes)
		(on_board yes)
		(dnp no)
		(fields_autoplaced yes)
		(property "Reference" "C341"
			(at 284.48 31.7436 90)
			(effects
				(font
					(size 1.27 1.27)
				)
				(justify right)
			)
		)
		(property "Value" "C_22u_25V_0805"
			(at 292.1 16.51 0)
			(effects
				(font
					(size 1.27 1.27)
					(thickness 0.15)
				)
				(justify left bottom)
				(hide yes)
			)
		)
		(property "Footprint" "antmicro-footprints:C_0805_2012Metric"
			(at 294.64 16.51 0)
			(effects
				(font
					(size 1.27 1.27)
					(thickness 0.15)
				)
				(justify left bottom)
				(hide yes)
			)
		)
		(property "Datasheet" "https://product.samsungsem.com/mlcc/CL21A226MAYNNN.do"
			(at 297.18 16.51 0)
			(effects
				(font
					(size 1.27 1.27)
					(thickness 0.15)
				)
				(justify left bottom)
				(hide yes)
			)
		)
		(property "Description" ""
			(at 281.94 36.83 0)
			(effects
				(font
					(size 1.27 1.27)
				)
			)
		)
		(property "Manufacturer" "Samsung Electro-Mechanics"
			(at 302.26 16.51 0)
			(effects
				(font
					(size 1.27 1.27)
					(thickness 0.15)
				)
				(justify left bottom)
				(hide yes)
			)
		)
		(property "MPN" "CL21A226MAYNNNE"
			(at 299.72 16.51 0)
			(effects
				(font
					(size 1.27 1.27)
					(thickness 0.15)
				)
				(justify left bottom)
				(hide yes)
			)
		)
		(property "Val" "22u"
			(at 284.48 34.2836 90)
			(effects
				(font
					(size 1.27 1.27)
					(thickness 0.15)
				)
				(justify right)
			)
		)
		(property "License" "Apache-2.0"
			(at 304.8 16.51 0)
			(effects
				(font
					(size 1.27 1.27)
					(thickness 0.15)
				)
				(justify left bottom)
				(hide yes)
			)
		)
		(property "Author" "Antmicro"
			(at 307.34 16.51 0)
			(effects
				(font
					(size 1.27 1.27)
					(thickness 0.15)
				)
				(justify left bottom)
				(hide yes)
			)
		)
		(property "Voltage" "25V"
			(at 284.48 36.8236 90)
			(effects
				(font
					(size 1.27 1.27)
				)
				(justify right)
			)
		)
		(property "Dielectric" "X5R"
			(at 312.42 16.51 0)
			(effects
				(font
					(size 1.27 1.27)
				)
				(justify left bottom)
				(hide yes)
			)
		)
		(pin "1"
		)
		(pin "2"
		)
		(instances
			(project "k410t-devboard"
				(path ""
					(reference "C341")
					(unit 1)
				)
			)
		)
	)
	(symbol
		(lib_id "antmicropower:GND")
		(at 119.38 105.41 0)
		(unit 1)
		(exclude_from_sim no)
		(in_bom yes)
		(on_board yes)
		(dnp no)
		(fields_autoplaced yes)
		(property "Reference" "#PWR0375"
			(at 119.38 111.76 0)
			(effects
				(font
					(size 1.27 1.27)
				)
				(hide yes)
			)
		)
		(property "Value" "GND"
			(at 119.38 109.22 0)
			(effects
				(font
					(size 1.27 1.27)
				)
			)
		)
		(property "Footprint" ""
			(at 128.27 113.03 0)
			(effects
				(font
					(size 1.27 1.27)
					(thickness 0.15)
				)
				(justify left bottom)
				(hide yes)
			)
		)
		(property "Datasheet" ""
			(at 128.27 118.11 0)
			(effects
				(font
					(size 1.27 1.27)
					(thickness 0.15)
				)
				(justify left bottom)
				(hide yes)
			)
		)
		(property "Description" ""
			(at 119.38 105.41 0)
			(effects
				(font
					(size 1.27 1.27)
				)
			)
		)
		(property "Author" "Antmicro"
			(at 128.27 113.03 0)
			(effects
				(font
					(size 1.27 1.27)
					(thickness 0.15)
				)
				(justify left bottom)
				(hide yes)
			)
		)
		(property "License" "Apache-2.0"
			(at 128.27 115.57 0)
			(effects
				(font
					(size 1.27 1.27)
					(thickness 0.15)
				)
				(justify left bottom)
				(hide yes)
			)
		)
		(pin "1"
		)
		(instances
			(project "k410t-devboard"
				(path ""
					(reference "#PWR0375")
					(unit 1)
				)
			)
		)
	)
	(symbol
		(lib_id "antmicroResistors0402:R_0R_0402")
		(at 199.39 50.8 180)
		(unit 1)
		(exclude_from_sim no)
		(in_bom yes)
		(on_board yes)
		(dnp no)
		(property "Reference" "R308"
			(at 201.93 49.53 0)
			(effects
				(font
					(size 1.27 1.27)
				)
			)
		)
		(property "Value" "R_0R_0402"
			(at 179.07 38.1 0)
			(effects
				(font
					(size 1.27 1.27)
					(thickness 0.15)
				)
				(justify left bottom)
				(hide yes)
			)
		)
		(property "Footprint" "antmicro-footprints:R_0402_1005Metric"
			(at 179.07 35.56 0)
			(effects
				(font
					(size 1.27 1.27)
					(thickness 0.15)
				)
				(justify left bottom)
				(hide yes)
			)
		)
		(property "Datasheet" "https://industrial.panasonic.com/cdbs/www-data/pdf/RDA0000/AOA0000C301.pdf"
			(at 179.07 33.02 0)
			(effects
				(font
					(size 1.27 1.27)
					(thickness 0.15)
				)
				(justify left bottom)
				(hide yes)
			)
		)
		(property "Description" ""
			(at 199.39 50.8 0)
			(effects
				(font
					(size 1.27 1.27)
				)
			)
		)
		(property "Manufacturer" "Panasonic"
			(at 179.07 27.94 0)
			(effects
				(font
					(size 1.27 1.27)
					(thickness 0.15)
				)
				(justify left bottom)
				(hide yes)
			)
		)
		(property "MPN" "ERJ2GE0R00X"
			(at 179.07 30.48 0)
			(effects
				(font
					(size 1.27 1.27)
					(thickness 0.15)
				)
				(justify left bottom)
				(hide yes)
			)
		)
		(property "Val" "0R"
			(at 193.04 49.53 0)
			(effects
				(font
					(size 1.27 1.27)
					(thickness 0.15)
				)
			)
		)
		(property "License" "Apache-2.0"
			(at 179.07 25.4 0)
			(effects
				(font
					(size 1.27 1.27)
					(thickness 0.15)
				)
				(justify left bottom)
				(hide yes)
			)
		)
		(property "Author" "Antmicro"
			(at 179.07 22.86 0)
			(effects
				(font
					(size 1.27 1.27)
					(thickness 0.15)
				)
				(justify left bottom)
				(hide yes)
			)
		)
		(property "Tolerance" "~"
			(at 179.07 40.64 0)
			(effects
				(font
					(size 1.27 1.27)
				)
				(justify left bottom)
				(hide yes)
			)
		)
		(property "Current" "1A"
			(at 196.85 46.99 0)
			(effects
				(font
					(size 1.27 1.27)
					(thickness 0.15)
				)
				(hide yes)
			)
		)
		(pin "1"
		)
		(pin "2"
		)
		(instances
			(project "k410t-devboard"
				(path ""
					(reference "R308")
					(unit 1)
				)
			)
		)
	)
	(symbol
		(lib_id "antmicropower:GND")
		(at 100.33 64.77 0)
		(unit 1)
		(exclude_from_sim no)
		(in_bom yes)
		(on_board yes)
		(dnp no)
		(property "Reference" "#PWR0373"
			(at 100.33 71.12 0)
			(effects
				(font
					(size 1.27 1.27)
				)
				(hide yes)
			)
		)
		(property "Value" "GND"
			(at 100.33 68.58 0)
			(effects
				(font
					(size 1.27 1.27)
				)
			)
		)
		(property "Footprint" ""
			(at 109.22 72.39 0)
			(effects
				(font
					(size 1.27 1.27)
					(thickness 0.15)
				)
				(justify left bottom)
				(hide yes)
			)
		)
		(property "Datasheet" ""
			(at 109.22 77.47 0)
			(effects
				(font
					(size 1.27 1.27)
					(thickness 0.15)
				)
				(justify left bottom)
				(hide yes)
			)
		)
		(property "Description" ""
			(at 100.33 64.77 0)
			(effects
				(font
					(size 1.27 1.27)
				)
			)
		)
		(property "Author" "Antmicro"
			(at 109.22 72.39 0)
			(effects
				(font
					(size 1.27 1.27)
					(thickness 0.15)
				)
				(justify left bottom)
				(hide yes)
			)
		)
		(property "License" "Apache-2.0"
			(at 109.22 74.93 0)
			(effects
				(font
					(size 1.27 1.27)
					(thickness 0.15)
				)
				(justify left bottom)
				(hide yes)
			)
		)
		(pin "1"
		)
		(instances
			(project "k410t-devboard"
				(path ""
					(reference "#PWR0373")
					(unit 1)
				)
			)
		)
	)
	(symbol
		(lib_id "k410t-devboard:Net-Tie_2")
		(at 238.76 121.92 90)
		(unit 1)
		(exclude_from_sim no)
		(in_bom yes)
		(on_board yes)
		(dnp no)
		(fields_autoplaced yes)
		(property "Reference" "NT37"
			(at 237.49 121.92 0)
			(effects
				(font
					(size 1.27 1.27)
				)
				(hide yes)
			)
		)
		(property "Value" "Net-Tie_2"
			(at 240.03 120.0149 90)
			(effects
				(font
					(size 1.27 1.27)
					(thickness 0.15)
				)
				(justify right)
				(hide yes)
			)
		)
		(property "Footprint" "antmicro-footprints:NetTie-2_SMD_Pad0.127mm"
			(at 243.84 100.33 0)
			(effects
				(font
					(size 1.27 1.27)
					(thickness 0.15)
				)
				(justify left bottom)
				(hide yes)
			)
		)
		(property "Datasheet" ""
			(at 246.38 100.33 0)
			(effects
				(font
					(size 1.27 1.27)
					(thickness 0.15)
				)
				(justify left bottom)
				(hide yes)
			)
		)
		(property "Description" ""
			(at 238.76 121.92 0)
			(effects
				(font
					(size 1.27 1.27)
				)
			)
		)
		(property "MPN" ""
			(at 247.65 100.33 0)
			(effects
				(font
					(size 1.27 1.27)
				)
				(justify left)
				(hide yes)
			)
		)
		(property "Manufacturer" ""
			(at 250.19 100.33 0)
			(effects
				(font
					(size 1.27 1.27)
				)
				(justify left)
				(hide yes)
			)
		)
		(property "Author" "Antmicro"
			(at 254 100.33 0)
			(effects
				(font
					(size 1.27 1.27)
					(thickness 0.15)
				)
				(justify left bottom)
				(hide yes)
			)
		)
		(property "License" "Apache-2.0"
			(at 256.54 100.33 0)
			(effects
				(font
					(size 1.27 1.27)
					(thickness 0.15)
				)
				(justify left bottom)
				(hide yes)
			)
		)
		(pin "1"
		)
		(pin "2"
		)
		(instances
			(project "k410t-devboard"
				(path ""
					(reference "NT37")
					(unit 1)
				)
			)
		)
	)
	(symbol
		(lib_id "antmicroCapacitors0603:C_22u_0603")
		(at 110.49 255.27 90)
		(unit 1)
		(exclude_from_sim no)
		(in_bom yes)
		(on_board yes)
		(dnp no)
		(property "Reference" "C333"
			(at 111.125 250.825 90)
			(effects
				(font
					(size 1.27 1.27)
				)
				(justify right)
			)
		)
		(property "Value" "C_22u_0603"
			(at 120.65 234.95 0)
			(effects
				(font
					(size 1.27 1.27)
					(thickness 0.15)
				)
				(justify left bottom)
				(hide yes)
			)
		)
		(property "Footprint" "antmicro-footprints:C_0603_1608Metric"
			(at 123.19 234.95 0)
			(effects
				(font
					(size 1.27 1.27)
					(thickness 0.15)
				)
				(justify left bottom)
				(hide yes)
			)
		)
		(property "Datasheet" "https://www.murata.com/products/productdetail?partno=GRM188R60J226MEA0%23"
			(at 125.73 234.95 0)
			(effects
				(font
					(size 1.27 1.27)
					(thickness 0.15)
				)
				(justify left bottom)
				(hide yes)
			)
		)
		(property "Description" ""
			(at 110.49 255.27 0)
			(effects
				(font
					(size 1.27 1.27)
				)
			)
		)
		(property "Manufacturer" "Murata"
			(at 130.81 234.95 0)
			(effects
				(font
					(size 1.27 1.27)
					(thickness 0.15)
				)
				(justify left bottom)
				(hide yes)
			)
		)
		(property "MPN" "GRM188R60J226MEA0D"
			(at 128.27 234.95 0)
			(effects
				(font
					(size 1.27 1.27)
					(thickness 0.15)
				)
				(justify left bottom)
				(hide yes)
			)
		)
		(property "Val" "22u"
			(at 111.125 255.27 90)
			(effects
				(font
					(size 1.27 1.27)
					(thickness 0.15)
				)
				(justify right)
			)
		)
		(property "License" "Apache-2.0"
			(at 133.35 234.95 0)
			(effects
				(font
					(size 1.27 1.27)
					(thickness 0.15)
				)
				(justify left bottom)
				(hide yes)
			)
		)
		(property "Author" "Antmicro"
			(at 135.89 234.95 0)
			(effects
				(font
					(size 1.27 1.27)
					(thickness 0.15)
				)
				(justify left bottom)
				(hide yes)
			)
		)
		(property "Voltage" ""
			(at 138.43 234.95 0)
			(effects
				(font
					(size 1.27 1.27)
				)
				(justify left bottom)
				(hide yes)
			)
		)
		(property "Dielectric" ""
			(at 140.97 234.95 0)
			(effects
				(font
					(size 1.27 1.27)
				)
				(justify left bottom)
				(hide yes)
			)
		)
		(pin "1"
		)
		(pin "2"
		)
		(instances
			(project "k410t-devboard"
				(path ""
					(reference "C333")
					(unit 1)
				)
			)
		)
	)
	(symbol
		(lib_id "antmicroCapacitors0402:C_100n_0402")
		(at 377.19 170.18 90)
		(unit 1)
		(exclude_from_sim no)
		(in_bom yes)
		(on_board yes)
		(dnp no)
		(fields_autoplaced yes)
		(property "Reference" "C362"
			(at 379.73 166.3635 90)
			(effects
				(font
					(size 1.27 1.27)
				)
				(justify right)
			)
		)
		(property "Value" "C_100n_0402"
			(at 387.35 149.86 0)
			(effects
				(font
					(size 1.27 1.27)
					(thickness 0.15)
				)
				(justify left bottom)
				(hide yes)
			)
		)
		(property "Footprint" "antmicro-footprints:C_0402_1005Metric"
			(at 389.89 149.86 0)
			(effects
				(font
					(size 1.27 1.27)
					(thickness 0.15)
				)
				(justify left bottom)
				(hide yes)
			)
		)
		(property "Datasheet" "https://www.murata.com/products/productdetail?partno=GRM155R61H104KE14%23"
			(at 392.43 149.86 0)
			(effects
				(font
					(size 1.27 1.27)
					(thickness 0.15)
				)
				(justify left bottom)
				(hide yes)
			)
		)
		(property "Description" ""
			(at 377.19 170.18 0)
			(effects
				(font
					(size 1.27 1.27)
				)
			)
		)
		(property "Manufacturer" "Murata"
			(at 397.51 149.86 0)
			(effects
				(font
					(size 1.27 1.27)
					(thickness 0.15)
				)
				(justify left bottom)
				(hide yes)
			)
		)
		(property "MPN" "GRM155R61H104KE14D"
			(at 394.97 149.86 0)
			(effects
				(font
					(size 1.27 1.27)
					(thickness 0.15)
				)
				(justify left bottom)
				(hide yes)
			)
		)
		(property "Val" "100n"
			(at 379.73 168.9035 90)
			(effects
				(font
					(size 1.27 1.27)
					(thickness 0.15)
				)
				(justify right)
			)
		)
		(property "License" "Apache-2.0"
			(at 400.05 149.86 0)
			(effects
				(font
					(size 1.27 1.27)
					(thickness 0.15)
				)
				(justify left bottom)
				(hide yes)
			)
		)
		(property "Author" "Antmicro"
			(at 402.59 149.86 0)
			(effects
				(font
					(size 1.27 1.27)
					(thickness 0.15)
				)
				(justify left bottom)
				(hide yes)
			)
		)
		(property "Voltage" "50V"
			(at 405.13 149.86 0)
			(effects
				(font
					(size 1.27 1.27)
				)
				(justify left bottom)
				(hide yes)
			)
		)
		(property "Dielectric" "X5R"
			(at 407.67 149.86 0)
			(effects
				(font
					(size 1.27 1.27)
				)
				(justify left bottom)
				(hide yes)
			)
		)
		(pin "1"
		)
		(pin "2"
		)
		(instances
			(project "k410t-devboard"
				(path ""
					(reference "C362")
					(unit 1)
				)
			)
		)
	)
	(symbol
		(lib_id "antmicropower:PWR_FLAG")
		(at 118.11 93.98 0)
		(unit 1)
		(exclude_from_sim no)
		(in_bom yes)
		(on_board yes)
		(dnp no)
		(fields_autoplaced yes)
		(property "Reference" "#FLG0102"
			(at 118.11 92.075 0)
			(effects
				(font
					(size 1.27 1.27)
				)
				(hide yes)
			)
		)
		(property "Value" "PWR_FLAG"
			(at 118.11 90.17 0)
			(effects
				(font
					(size 1.27 1.27)
				)
			)
		)
		(property "Footprint" ""
			(at 118.11 93.98 0)
			(effects
				(font
					(size 1.27 1.27)
				)
				(hide yes)
			)
		)
		(property "Datasheet" ""
			(at 118.11 93.98 0)
			(effects
				(font
					(size 1.27 1.27)
				)
				(hide yes)
			)
		)
		(property "Description" ""
			(at 118.11 93.98 0)
			(effects
				(font
					(size 1.27 1.27)
				)
			)
		)
		(pin "1"
		)
		(instances
			(project "k410t-devboard"
				(path ""
					(reference "#FLG0102")
					(unit 1)
				)
			)
		)
	)
	(symbol
		(lib_id "antmicropower:+1V0")
		(at 403.86 36.83 0)
		(unit 1)
		(exclude_from_sim no)
		(in_bom yes)
		(on_board yes)
		(dnp no)
		(fields_autoplaced yes)
		(property "Reference" "#PWR0408"
			(at 403.86 40.64 0)
			(effects
				(font
					(size 1.27 1.27)
				)
				(hide yes)
			)
		)
		(property "Value" "+1V0"
			(at 403.86 33.274 0)
			(effects
				(font
					(size 1.27 1.27)
				)
			)
		)
		(property "Footprint" ""
			(at 403.86 36.83 0)
			(effects
				(font
					(size 1.27 1.27)
				)
				(hide yes)
			)
		)
		(property "Datasheet" ""
			(at 403.86 36.83 0)
			(effects
				(font
					(size 1.27 1.27)
				)
				(hide yes)
			)
		)
		(property "Description" ""
			(at 403.86 36.83 0)
			(effects
				(font
					(size 1.27 1.27)
				)
			)
		)
		(pin "1"
		)
		(instances
			(project "k410t-devboard"
				(path ""
					(reference "#PWR0408")
					(unit 1)
				)
			)
		)
	)
	(symbol
		(lib_id "k410t-devboard:Net-Tie_2")
		(at 201.93 133.35 90)
		(unit 1)
		(exclude_from_sim no)
		(in_bom yes)
		(on_board yes)
		(dnp no)
		(fields_autoplaced yes)
		(property "Reference" "NT36"
			(at 200.66 133.35 0)
			(effects
				(font
					(size 1.27 1.27)
				)
				(hide yes)
			)
		)
		(property "Value" "Net-Tie_2"
			(at 203.835 131.4449 90)
			(effects
				(font
					(size 1.27 1.27)
					(thickness 0.15)
				)
				(justify right)
				(hide yes)
			)
		)
		(property "Footprint" "antmicro-footprints:NetTie-2_SMD_Pad0.127mm"
			(at 207.01 111.76 0)
			(effects
				(font
					(size 1.27 1.27)
					(thickness 0.15)
				)
				(justify left bottom)
				(hide yes)
			)
		)
		(property "Datasheet" ""
			(at 209.55 111.76 0)
			(effects
				(font
					(size 1.27 1.27)
					(thickness 0.15)
				)
				(justify left bottom)
				(hide yes)
			)
		)
		(property "Description" ""
			(at 201.93 133.35 0)
			(effects
				(font
					(size 1.27 1.27)
				)
			)
		)
		(property "MPN" ""
			(at 210.82 111.76 0)
			(effects
				(font
					(size 1.27 1.27)
				)
				(justify left)
				(hide yes)
			)
		)
		(property "Manufacturer" ""
			(at 213.36 111.76 0)
			(effects
				(font
					(size 1.27 1.27)
				)
				(justify left)
				(hide yes)
			)
		)
		(property "Author" "Antmicro"
			(at 217.17 111.76 0)
			(effects
				(font
					(size 1.27 1.27)
					(thickness 0.15)
				)
				(justify left bottom)
				(hide yes)
			)
		)
		(property "License" "Apache-2.0"
			(at 219.71 111.76 0)
			(effects
				(font
					(size 1.27 1.27)
					(thickness 0.15)
				)
				(justify left bottom)
				(hide yes)
			)
		)
		(pin "1"
		)
		(pin "2"
		)
		(instances
			(project "k410t-devboard"
				(path ""
					(reference "NT36")
					(unit 1)
				)
			)
		)
	)
	(symbol
		(lib_id "antmicropower:GND")
		(at 379.73 57.15 0)
		(unit 1)
		(exclude_from_sim no)
		(in_bom yes)
		(on_board yes)
		(dnp no)
		(fields_autoplaced yes)
		(property "Reference" "#PWR0452"
			(at 379.73 63.5 0)
			(effects
				(font
					(size 1.27 1.27)
				)
				(hide yes)
			)
		)
		(property "Value" "GND"
			(at 379.73 60.96 0)
			(effects
				(font
					(size 1.27 1.27)
				)
			)
		)
		(property "Footprint" ""
			(at 388.62 64.77 0)
			(effects
				(font
					(size 1.27 1.27)
					(thickness 0.15)
				)
				(justify left bottom)
				(hide yes)
			)
		)
		(property "Datasheet" ""
			(at 388.62 69.85 0)
			(effects
				(font
					(size 1.27 1.27)
					(thickness 0.15)
				)
				(justify left bottom)
				(hide yes)
			)
		)
		(property "Description" ""
			(at 379.73 57.15 0)
			(effects
				(font
					(size 1.27 1.27)
				)
			)
		)
		(property "Author" "Antmicro"
			(at 388.62 64.77 0)
			(effects
				(font
					(size 1.27 1.27)
					(thickness 0.15)
				)
				(justify left bottom)
				(hide yes)
			)
		)
		(property "License" "Apache-2.0"
			(at 388.62 67.31 0)
			(effects
				(font
					(size 1.27 1.27)
					(thickness 0.15)
				)
				(justify left bottom)
				(hide yes)
			)
		)
		(pin "1"
		)
		(instances
			(project "k410t-devboard"
				(path ""
					(reference "#PWR0452")
					(unit 1)
				)
			)
		)
	)
	(symbol
		(lib_id "antmicroCapacitors0402:C_10u_0402")
		(at 312.42 204.47 90)
		(unit 1)
		(exclude_from_sim no)
		(in_bom yes)
		(on_board yes)
		(dnp no)
		(property "Reference" "C349"
			(at 313.055 200.025 90)
			(effects
				(font
					(size 1.27 1.27)
				)
				(justify right)
			)
		)
		(property "Value" "C_10u_0402"
			(at 322.58 184.15 0)
			(effects
				(font
					(size 1.27 1.27)
					(thickness 0.15)
				)
				(justify left bottom)
				(hide yes)
			)
		)
		(property "Footprint" "antmicro-footprints:C_0402_1005Metric"
			(at 325.12 184.15 0)
			(effects
				(font
					(size 1.27 1.27)
					(thickness 0.15)
				)
				(justify left bottom)
				(hide yes)
			)
		)
		(property "Datasheet" "https://www.yageo.com/en/Chart/Download/pdf/CC0402MRX5R5BB106"
			(at 327.66 184.15 0)
			(effects
				(font
					(size 1.27 1.27)
					(thickness 0.15)
				)
				(justify left bottom)
				(hide yes)
			)
		)
		(property "Description" ""
			(at 312.42 204.47 0)
			(effects
				(font
					(size 1.27 1.27)
				)
			)
		)
		(property "Manufacturer" "YAGEO"
			(at 332.74 184.15 0)
			(effects
				(font
					(size 1.27 1.27)
					(thickness 0.15)
				)
				(justify left bottom)
				(hide yes)
			)
		)
		(property "MPN" "CC0402MRX5R5BB106"
			(at 330.2 184.15 0)
			(effects
				(font
					(size 1.27 1.27)
					(thickness 0.15)
				)
				(justify left bottom)
				(hide yes)
			)
		)
		(property "Val" "10u"
			(at 313.055 203.835 90)
			(effects
				(font
					(size 1.27 1.27)
					(thickness 0.15)
				)
				(justify right)
			)
		)
		(property "License" "Apache-2.0"
			(at 335.28 184.15 0)
			(effects
				(font
					(size 1.27 1.27)
					(thickness 0.15)
				)
				(justify left bottom)
				(hide yes)
			)
		)
		(property "Author" "Antmicro"
			(at 337.82 184.15 0)
			(effects
				(font
					(size 1.27 1.27)
					(thickness 0.15)
				)
				(justify left bottom)
				(hide yes)
			)
		)
		(property "Voltage" ""
			(at 340.36 184.15 0)
			(effects
				(font
					(size 1.27 1.27)
				)
				(justify left bottom)
				(hide yes)
			)
		)
		(property "Dielectric" ""
			(at 342.9 184.15 0)
			(effects
				(font
					(size 1.27 1.27)
				)
				(justify left bottom)
				(hide yes)
			)
		)
		(pin "1"
		)
		(pin "2"
		)
		(instances
			(project "k410t-devboard"
				(path ""
					(reference "C349")
					(unit 1)
				)
			)
		)
	)
	(symbol
		(lib_id "antmicroTestPoints:TP_0.75mm_SMD")
		(at 71.12 222.25 270)
		(unit 1)
		(exclude_from_sim no)
		(in_bom yes)
		(on_board yes)
		(dnp no)
		(property "Reference" "TP8"
			(at 73.025 227.33 90)
			(effects
				(font
					(size 1.27 1.27)
				)
				(justify right)
			)
		)
		(property "Value" "TP_0.75mm_SMD"
			(at 68.58 222.25 0)
			(effects
				(font
					(size 1.27 1.27)
				)
				(hide yes)
			)
		)
		(property "Footprint" "antmicro-footprints:TP_SMD_0.75mm"
			(at 76.2 227.33 0)
			(effects
				(font
					(size 1.27 1.27)
				)
				(justify left)
				(hide yes)
			)
		)
		(property "Datasheet" ""
			(at 78.74 227.33 0)
			(effects
				(font
					(size 1.27 1.27)
				)
				(justify left)
				(hide yes)
			)
		)
		(property "Description" ""
			(at 71.12 222.25 0)
			(effects
				(font
					(size 1.27 1.27)
				)
			)
		)
		(property "MPN" ""
			(at 71.12 222.25 0)
			(effects
				(font
					(size 1.27 1.27)
				)
				(hide yes)
			)
		)
		(property "Manufacturer" ""
			(at 71.12 222.25 0)
			(effects
				(font
					(size 1.27 1.27)
				)
				(hide yes)
			)
		)
		(property "Author" "Antmicro"
			(at 55.88 237.49 0)
			(effects
				(font
					(size 1.27 1.27)
					(thickness 0.15)
				)
				(justify left bottom)
				(hide yes)
			)
		)
		(property "License" "Apache-2.0"
			(at 53.34 237.49 0)
			(effects
				(font
					(size 1.27 1.27)
					(thickness 0.15)
				)
				(justify left bottom)
				(hide yes)
			)
		)
		(pin "1"
		)
		(instances
			(project "k410t-devboard"
				(path ""
					(reference "TP8")
					(unit 1)
				)
			)
		)
	)
	(symbol
		(lib_id "antmicroCapacitors0603:C_22u_0603")
		(at 110.49 123.19 90)
		(unit 1)
		(exclude_from_sim no)
		(in_bom yes)
		(on_board yes)
		(dnp no)
		(property "Reference" "C323"
			(at 111.125 118.745 90)
			(effects
				(font
					(size 1.27 1.27)
				)
				(justify right)
			)
		)
		(property "Value" "C_22u_0603"
			(at 120.65 102.87 0)
			(effects
				(font
					(size 1.27 1.27)
					(thickness 0.15)
				)
				(justify left bottom)
				(hide yes)
			)
		)
		(property "Footprint" "antmicro-footprints:C_0603_1608Metric"
			(at 123.19 102.87 0)
			(effects
				(font
					(size 1.27 1.27)
					(thickness 0.15)
				)
				(justify left bottom)
				(hide yes)
			)
		)
		(property "Datasheet" "https://www.murata.com/products/productdetail?partno=GRM188R60J226MEA0%23"
			(at 125.73 102.87 0)
			(effects
				(font
					(size 1.27 1.27)
					(thickness 0.15)
				)
				(justify left bottom)
				(hide yes)
			)
		)
		(property "Description" ""
			(at 110.49 123.19 0)
			(effects
				(font
					(size 1.27 1.27)
				)
			)
		)
		(property "Manufacturer" "Murata"
			(at 130.81 102.87 0)
			(effects
				(font
					(size 1.27 1.27)
					(thickness 0.15)
				)
				(justify left bottom)
				(hide yes)
			)
		)
		(property "MPN" "GRM188R60J226MEA0D"
			(at 128.27 102.87 0)
			(effects
				(font
					(size 1.27 1.27)
					(thickness 0.15)
				)
				(justify left bottom)
				(hide yes)
			)
		)
		(property "Val" "22u"
			(at 111.125 122.555 90)
			(effects
				(font
					(size 1.27 1.27)
					(thickness 0.15)
				)
				(justify right)
			)
		)
		(property "License" "Apache-2.0"
			(at 133.35 102.87 0)
			(effects
				(font
					(size 1.27 1.27)
					(thickness 0.15)
				)
				(justify left bottom)
				(hide yes)
			)
		)
		(property "Author" "Antmicro"
			(at 135.89 102.87 0)
			(effects
				(font
					(size 1.27 1.27)
					(thickness 0.15)
				)
				(justify left bottom)
				(hide yes)
			)
		)
		(property "Voltage" ""
			(at 138.43 102.87 0)
			(effects
				(font
					(size 1.27 1.27)
				)
				(justify left bottom)
				(hide yes)
			)
		)
		(property "Dielectric" ""
			(at 140.97 102.87 0)
			(effects
				(font
					(size 1.27 1.27)
				)
				(justify left bottom)
				(hide yes)
			)
		)
		(pin "1"
		)
		(pin "2"
		)
		(instances
			(project "k410t-devboard"
				(path ""
					(reference "C323")
					(unit 1)
				)
			)
		)
	)
	(symbol
		(lib_id "antmicroResistors0402:R_10k_0402")
		(at 302.26 228.6 90)
		(unit 1)
		(exclude_from_sim no)
		(in_bom yes)
		(on_board yes)
		(dnp no)
		(fields_autoplaced yes)
		(property "Reference" "R323"
			(at 304.165 224.7899 90)
			(effects
				(font
					(size 1.27 1.27)
				)
				(justify right)
			)
		)
		(property "Value" "R_10k_0402"
			(at 314.96 208.28 0)
			(effects
				(font
					(size 1.27 1.27)
					(thickness 0.15)
				)
				(justify left bottom)
				(hide yes)
			)
		)
		(property "Footprint" "antmicro-footprints:R_0402_1005Metric"
			(at 317.5 208.28 0)
			(effects
				(font
					(size 1.27 1.27)
					(thickness 0.15)
				)
				(justify left bottom)
				(hide yes)
			)
		)
		(property "Datasheet" "https://www.bourns.com/docs/product-datasheets/cr.pdf"
			(at 320.04 208.28 0)
			(effects
				(font
					(size 1.27 1.27)
					(thickness 0.15)
				)
				(justify left bottom)
				(hide yes)
			)
		)
		(property "Description" ""
			(at 302.26 228.6 0)
			(effects
				(font
					(size 1.27 1.27)
				)
			)
		)
		(property "Manufacturer" "Bourns"
			(at 325.12 208.28 0)
			(effects
				(font
					(size 1.27 1.27)
					(thickness 0.15)
				)
				(justify left bottom)
				(hide yes)
			)
		)
		(property "MPN" "CR0402-FX-1002GLF"
			(at 322.58 208.28 0)
			(effects
				(font
					(size 1.27 1.27)
					(thickness 0.15)
				)
				(justify left bottom)
				(hide yes)
			)
		)
		(property "Val" "10k"
			(at 304.165 227.3299 90)
			(effects
				(font
					(size 1.27 1.27)
					(thickness 0.15)
				)
				(justify right)
			)
		)
		(property "License" "Apache-2.0"
			(at 327.66 208.28 0)
			(effects
				(font
					(size 1.27 1.27)
					(thickness 0.15)
				)
				(justify left bottom)
				(hide yes)
			)
		)
		(property "Author" "Antmicro"
			(at 330.2 208.28 0)
			(effects
				(font
					(size 1.27 1.27)
					(thickness 0.15)
				)
				(justify left bottom)
				(hide yes)
			)
		)
		(property "Tolerance" "1%"
			(at 312.42 208.28 0)
			(effects
				(font
					(size 1.27 1.27)
				)
				(justify left bottom)
				(hide yes)
			)
		)
		(pin "1"
		)
		(pin "2"
		)
		(instances
			(project "k410t-devboard"
				(path ""
					(reference "R323")
					(unit 1)
				)
			)
		)
	)
	(symbol
		(lib_id "antmicroResistors0402:R_0R_0402")
		(at 186.69 113.03 90)
		(unit 1)
		(exclude_from_sim no)
		(in_bom no)
		(on_board yes)
		(dnp yes)
		(property "Reference" "R297"
			(at 189.23 109.2199 90)
			(effects
				(font
					(size 1.27 1.27)
				)
				(justify right)
			)
		)
		(property "Value" "R_0R_0402"
			(at 199.39 92.71 0)
			(effects
				(font
					(size 1.27 1.27)
					(thickness 0.15)
				)
				(justify left bottom)
				(hide yes)
			)
		)
		(property "Footprint" "antmicro-footprints:R_0402_1005Metric"
			(at 201.93 92.71 0)
			(effects
				(font
					(size 1.27 1.27)
					(thickness 0.15)
				)
				(justify left bottom)
				(hide yes)
			)
		)
		(property "Datasheet" "https://industrial.panasonic.com/cdbs/www-data/pdf/RDA0000/AOA0000C301.pdf"
			(at 204.47 92.71 0)
			(effects
				(font
					(size 1.27 1.27)
					(thickness 0.15)
				)
				(justify left bottom)
				(hide yes)
			)
		)
		(property "Description" ""
			(at 186.69 113.03 0)
			(effects
				(font
					(size 1.27 1.27)
				)
			)
		)
		(property "Manufacturer" "Panasonic"
			(at 209.55 92.71 0)
			(effects
				(font
					(size 1.27 1.27)
					(thickness 0.15)
				)
				(justify left bottom)
				(hide yes)
			)
		)
		(property "MPN" "ERJ2GE0R00X"
			(at 207.01 92.71 0)
			(effects
				(font
					(size 1.27 1.27)
					(thickness 0.15)
				)
				(justify left bottom)
				(hide yes)
			)
		)
		(property "Val" "0R"
			(at 189.23 111.7599 90)
			(effects
				(font
					(size 1.27 1.27)
					(thickness 0.15)
				)
				(justify right)
			)
		)
		(property "DNP" "DNP"
			(at 186.69 108.585 0)
			(effects
				(font
					(size 1.27 1.27)
				)
				(justify right)
			)
		)
		(property "License" "Apache-2.0"
			(at 212.09 92.71 0)
			(effects
				(font
					(size 1.27 1.27)
					(thickness 0.15)
				)
				(justify left bottom)
				(hide yes)
			)
		)
		(property "Author" "Antmicro"
			(at 214.63 92.71 0)
			(effects
				(font
					(size 1.27 1.27)
					(thickness 0.15)
				)
				(justify left bottom)
				(hide yes)
			)
		)
		(property "Tolerance" "~"
			(at 196.85 92.71 0)
			(effects
				(font
					(size 1.27 1.27)
				)
				(justify left bottom)
				(hide yes)
			)
		)
		(property "Current" "1A"
			(at 189.23 114.2999 90)
			(effects
				(font
					(size 1.27 1.27)
					(thickness 0.15)
				)
				(justify right)
				(hide yes)
			)
		)
		(pin "1"
		)
		(pin "2"
		)
		(instances
			(project "k410t-devboard"
				(path ""
					(reference "R297")
					(unit 1)
				)
			)
		)
	)
	(symbol
		(lib_id "antmicroPMICVoltageRegulatorsDCDCSwitchingRegulators:MPM54304GMN")
		(at 71.12 110.49 0)
		(unit 1)
		(exclude_from_sim no)
		(in_bom yes)
		(on_board yes)
		(dnp no)
		(property "Reference" "U31"
			(at 85.09 103.505 0)
			(effects
				(font
					(size 1.27 1.27)
				)
			)
		)
		(property "Value" "MPM54304GMN"
			(at 85.09 106.045 0)
			(effects
				(font
					(size 1.27 1.27)
				)
			)
		)
		(property "Footprint" "antmicro-footprints:LGA-33_7x7mm_P0.65mm"
			(at 93.98 138.43 0)
			(effects
				(font
					(size 1.27 1.27)
				)
				(hide yes)
			)
		)
		(property "Datasheet" "https://www.monolithicpower.com/en/documentview/productdocument/index/version/2/document_type/Datasheet/lang/en/sku/MPM54304/document_id/4982/"
			(at 167.64 140.97 0)
			(effects
				(font
					(size 1.27 1.27)
				)
				(hide yes)
			)
		)
		(property "Description" ""
			(at 71.12 110.49 0)
			(effects
				(font
					(size 1.27 1.27)
				)
			)
		)
		(property "MPN" "MPM54304GMN-0000"
			(at 81.28 135.89 0)
			(effects
				(font
					(size 1.27 1.27)
				)
				(hide yes)
			)
		)
		(property "Manufacturer" "Monolithic Power Systems"
			(at 80.01 133.35 0)
			(effects
				(font
					(size 1.27 1.27)
				)
				(hide yes)
			)
		)
		(property "Author" "Antmicro"
			(at 118.11 128.27 0)
			(effects
				(font
					(size 1.27 1.27)
					(thickness 0.15)
				)
				(justify left bottom)
				(hide yes)
			)
		)
		(property "License" "Apache-2.0"
			(at 118.11 130.81 0)
			(effects
				(font
					(size 1.27 1.27)
					(thickness 0.15)
				)
				(justify left bottom)
				(hide yes)
			)
		)
		(pin "1"
		)
		(pin "10"
		)
		(pin "11"
		)
		(pin "12"
		)
		(pin "13"
		)
		(pin "14"
		)
		(pin "15"
		)
		(pin "16"
		)
		(pin "17"
		)
		(pin "18"
		)
		(pin "19"
		)
		(pin "2"
		)
		(pin "20"
		)
		(pin "21"
		)
		(pin "22"
		)
		(pin "23"
		)
		(pin "24"
		)
		(pin "25"
		)
		(pin "26"
		)
		(pin "27"
		)
		(pin "28"
		)
		(pin "29"
		)
		(pin "3"
		)
		(pin "30"
		)
		(pin "31"
		)
		(pin "32"
		)
		(pin "33"
		)
		(pin "4"
		)
		(pin "5"
		)
		(pin "6"
		)
		(pin "7"
		)
		(pin "8"
		)
		(pin "9"
		)
		(instances
			(project "k410t-devboard"
				(path ""
					(reference "U31")
					(unit 1)
				)
			)
		)
	)
	(symbol
		(lib_id "antmicroPMICPowerSequencers:LM3880")
		(at 232.41 43.18 0)
		(unit 1)
		(exclude_from_sim no)
		(in_bom yes)
		(on_board yes)
		(dnp no)
		(fields_autoplaced yes)
		(property "Reference" "U36"
			(at 234.4294 40.64 0)
			(effects
				(font
					(size 1.27 1.27)
				)
				(justify left)
			)
		)
		(property "Value" "LM3880"
			(at 234.4294 43.18 0)
			(effects
				(font
					(size 1.27 1.27)
				)
				(justify left)
			)
		)
		(property "Footprint" "antmicro-footprints:SOT-23-6"
			(at 248.92 49.53 0)
			(effects
				(font
					(size 1.27 1.27)
				)
				(hide yes)
			)
		)
		(property "Datasheet" "http://www.ti.com/lit/ds/symlink/lm3880.pdf"
			(at 256.54 51.435 0)
			(effects
				(font
					(size 1.27 1.27)
				)
				(hide yes)
			)
		)
		(property "Description" ""
			(at 232.41 43.18 0)
			(effects
				(font
					(size 1.27 1.27)
				)
			)
		)
		(property "Manufacturer" "Texas Instruments"
			(at 243.205 53.34 0)
			(effects
				(font
					(size 1.27 1.27)
				)
				(hide yes)
			)
		)
		(property "MPN" "LM3880MFX-1AA/NOPB"
			(at 246.38 55.245 0)
			(effects
				(font
					(size 1.27 1.27)
				)
				(hide yes)
			)
		)
		(property "Author" "Antmicro"
			(at 257.81 63.5 0)
			(effects
				(font
					(size 1.27 1.27)
					(thickness 0.15)
				)
				(justify left bottom)
				(hide yes)
			)
		)
		(property "License" "Apache-2.0"
			(at 257.81 66.04 0)
			(effects
				(font
					(size 1.27 1.27)
					(thickness 0.15)
				)
				(justify left bottom)
				(hide yes)
			)
		)
		(pin "1"
		)
		(pin "2"
		)
		(pin "3"
		)
		(pin "4"
		)
		(pin "5"
		)
		(pin "6"
		)
		(instances
			(project "k410t-devboard"
				(path ""
					(reference "U36")
					(unit 1)
				)
			)
		)
	)
	(symbol
		(lib_id "antmicropower:+3.3V")
		(at 203.2 180.34 0)
		(unit 1)
		(exclude_from_sim no)
		(in_bom yes)
		(on_board yes)
		(dnp no)
		(fields_autoplaced yes)
		(property "Reference" "#PWR0370"
			(at 203.2 184.15 0)
			(effects
				(font
					(size 1.27 1.27)
				)
				(hide yes)
			)
		)
		(property "Value" "+3V3"
			(at 203.2 176.784 0)
			(effects
				(font
					(size 1.27 1.27)
				)
			)
		)
		(property "Footprint" ""
			(at 203.2 180.34 0)
			(effects
				(font
					(size 1.27 1.27)
				)
				(hide yes)
			)
		)
		(property "Datasheet" ""
			(at 203.2 180.34 0)
			(effects
				(font
					(size 1.27 1.27)
				)
				(hide yes)
			)
		)
		(property "Description" ""
			(at 203.2 180.34 0)
			(effects
				(font
					(size 1.27 1.27)
				)
			)
		)
		(pin "1"
		)
		(instances
			(project "k410t-devboard"
				(path ""
					(reference "#PWR0370")
					(unit 1)
				)
			)
		)
	)
	(symbol
		(lib_id "antmicropower:+0V675_VTT")
		(at 386.08 203.2 0)
		(unit 1)
		(exclude_from_sim no)
		(in_bom yes)
		(on_board yes)
		(dnp no)
		(property "Reference" "#PWR0407"
			(at 386.08 207.01 0)
			(effects
				(font
					(size 1.27 1.27)
				)
				(hide yes)
			)
		)
		(property "Value" "+0V675_VTT"
			(at 386.08 199.644 0)
			(effects
				(font
					(size 1.27 1.27)
				)
			)
		)
		(property "Footprint" ""
			(at 386.08 203.2 0)
			(effects
				(font
					(size 1.27 1.27)
				)
				(hide yes)
			)
		)
		(property "Datasheet" ""
			(at 386.08 203.2 0)
			(effects
				(font
					(size 1.27 1.27)
				)
				(hide yes)
			)
		)
		(property "Description" ""
			(at 386.08 203.2 0)
			(effects
				(font
					(size 1.27 1.27)
				)
			)
		)
		(pin "1"
		)
		(instances
			(project "k410t-devboard"
				(path ""
					(reference "#PWR0407")
					(unit 1)
				)
			)
		)
	)
	(symbol
		(lib_id "antmicropower:GND")
		(at 388.62 76.2 0)
		(unit 1)
		(exclude_from_sim no)
		(in_bom yes)
		(on_board yes)
		(dnp no)
		(fields_autoplaced yes)
		(property "Reference" "#PWR0454"
			(at 388.62 82.55 0)
			(effects
				(font
					(size 1.27 1.27)
				)
				(hide yes)
			)
		)
		(property "Value" "GND"
			(at 388.62 80.01 0)
			(effects
				(font
					(size 1.27 1.27)
				)
			)
		)
		(property "Footprint" ""
			(at 397.51 83.82 0)
			(effects
				(font
					(size 1.27 1.27)
					(thickness 0.15)
				)
				(justify left bottom)
				(hide yes)
			)
		)
		(property "Datasheet" ""
			(at 397.51 88.9 0)
			(effects
				(font
					(size 1.27 1.27)
					(thickness 0.15)
				)
				(justify left bottom)
				(hide yes)
			)
		)
		(property "Description" ""
			(at 388.62 76.2 0)
			(effects
				(font
					(size 1.27 1.27)
				)
			)
		)
		(property "Author" "Antmicro"
			(at 397.51 83.82 0)
			(effects
				(font
					(size 1.27 1.27)
					(thickness 0.15)
				)
				(justify left bottom)
				(hide yes)
			)
		)
		(property "License" "Apache-2.0"
			(at 397.51 86.36 0)
			(effects
				(font
					(size 1.27 1.27)
					(thickness 0.15)
				)
				(justify left bottom)
				(hide yes)
			)
		)
		(pin "1"
		)
		(instances
			(project "k410t-devboard"
				(path ""
					(reference "#PWR0454")
					(unit 1)
				)
			)
		)
	)
	(symbol
		(lib_id "antmicropower:GND")
		(at 351.79 166.37 0)
		(unit 1)
		(exclude_from_sim no)
		(in_bom yes)
		(on_board yes)
		(dnp no)
		(fields_autoplaced yes)
		(property "Reference" "#PWR0436"
			(at 351.79 172.72 0)
			(effects
				(font
					(size 1.27 1.27)
				)
				(hide yes)
			)
		)
		(property "Value" "GND"
			(at 351.79 170.18 0)
			(effects
				(font
					(size 1.27 1.27)
				)
			)
		)
		(property "Footprint" ""
			(at 360.68 173.99 0)
			(effects
				(font
					(size 1.27 1.27)
					(thickness 0.15)
				)
				(justify left bottom)
				(hide yes)
			)
		)
		(property "Datasheet" ""
			(at 360.68 179.07 0)
			(effects
				(font
					(size 1.27 1.27)
					(thickness 0.15)
				)
				(justify left bottom)
				(hide yes)
			)
		)
		(property "Description" ""
			(at 351.79 166.37 0)
			(effects
				(font
					(size 1.27 1.27)
				)
			)
		)
		(property "Author" "Antmicro"
			(at 360.68 173.99 0)
			(effects
				(font
					(size 1.27 1.27)
					(thickness 0.15)
				)
				(justify left bottom)
				(hide yes)
			)
		)
		(property "License" "Apache-2.0"
			(at 360.68 176.53 0)
			(effects
				(font
					(size 1.27 1.27)
					(thickness 0.15)
				)
				(justify left bottom)
				(hide yes)
			)
		)
		(pin "1"
		)
		(instances
			(project "k410t-devboard"
				(path ""
					(reference "#PWR0436")
					(unit 1)
				)
			)
		)
	)
	(symbol
		(lib_id "antmicroPMICVoltageRegulatorsDCDCSwitchingControllers:NCP51400MNTXG")
		(at 325.12 212.09 0)
		(unit 1)
		(exclude_from_sim no)
		(in_bom yes)
		(on_board yes)
		(dnp no)
		(property "Reference" "U39"
			(at 337.185 205.74 0)
			(effects
				(font
					(size 1.27 1.27)
				)
			)
		)
		(property "Value" "NCP51400MNTXG"
			(at 337.185 208.28 0)
			(effects
				(font
					(size 1.27 1.27)
				)
			)
		)
		(property "Footprint" "antmicro-footprints:DFN-10-1EP_3x3mm"
			(at 344.17 213.36 0)
			(effects
				(font
					(size 1.27 1.27)
				)
				(hide yes)
			)
		)
		(property "Datasheet" "https://www.mouser.com/datasheet/2/308/NCP51400_D-1812533.pdf"
			(at 375.92 215.9 0)
			(effects
				(font
					(size 1.27 1.27)
				)
				(hide yes)
			)
		)
		(property "Description" ""
			(at 325.12 212.09 0)
			(effects
				(font
					(size 1.27 1.27)
				)
			)
		)
		(property "MPN" "NCP51400MNTXG"
			(at 344.17 220.98 0)
			(effects
				(font
					(size 1.27 1.27)
				)
				(hide yes)
			)
		)
		(property "Manufacturer" "ON Semiconductor"
			(at 339.09 218.44 0)
			(effects
				(font
					(size 1.27 1.27)
				)
				(hide yes)
			)
		)
		(property "Author" "Antmicro"
			(at 363.22 231.14 0)
			(effects
				(font
					(size 1.27 1.27)
					(thickness 0.15)
				)
				(justify left bottom)
				(hide yes)
			)
		)
		(property "License" "Apache-2.0"
			(at 363.22 233.68 0)
			(effects
				(font
					(size 1.27 1.27)
					(thickness 0.15)
				)
				(justify left bottom)
				(hide yes)
			)
		)
		(pin "1"
		)
		(pin "10"
		)
		(pin "11"
		)
		(pin "2"
		)
		(pin "3"
		)
		(pin "4"
		)
		(pin "5"
		)
		(pin "6"
		)
		(pin "7"
		)
		(pin "8"
		)
		(pin "9"
		)
		(instances
			(project "k410t-devboard"
				(path ""
					(reference "U39")
					(unit 1)
				)
			)
		)
	)
	(symbol
		(lib_id "antmicropower:GND")
		(at 328.93 78.74 0)
		(unit 1)
		(exclude_from_sim no)
		(in_bom yes)
		(on_board yes)
		(dnp no)
		(fields_autoplaced yes)
		(property "Reference" "#PWR0424"
			(at 328.93 85.09 0)
			(effects
				(font
					(size 1.27 1.27)
				)
				(hide yes)
			)
		)
		(property "Value" "GND"
			(at 328.93 82.55 0)
			(effects
				(font
					(size 1.27 1.27)
				)
			)
		)
		(property "Footprint" ""
			(at 337.82 86.36 0)
			(effects
				(font
					(size 1.27 1.27)
					(thickness 0.15)
				)
				(justify left bottom)
				(hide yes)
			)
		)
		(property "Datasheet" ""
			(at 337.82 91.44 0)
			(effects
				(font
					(size 1.27 1.27)
					(thickness 0.15)
				)
				(justify left bottom)
				(hide yes)
			)
		)
		(property "Description" ""
			(at 328.93 78.74 0)
			(effects
				(font
					(size 1.27 1.27)
				)
			)
		)
		(property "Author" "Antmicro"
			(at 337.82 86.36 0)
			(effects
				(font
					(size 1.27 1.27)
					(thickness 0.15)
				)
				(justify left bottom)
				(hide yes)
			)
		)
		(property "License" "Apache-2.0"
			(at 337.82 88.9 0)
			(effects
				(font
					(size 1.27 1.27)
					(thickness 0.15)
				)
				(justify left bottom)
				(hide yes)
			)
		)
		(pin "1"
		)
		(instances
			(project "k410t-devboard"
				(path ""
					(reference "#PWR0424")
					(unit 1)
				)
			)
		)
	)
	(symbol
		(lib_id "antmicroPMICVoltageRegulatorsLinear:NCP718BSN330T1G")
		(at 26.67 39.37 0)
		(unit 1)
		(exclude_from_sim no)
		(in_bom yes)
		(on_board yes)
		(dnp no)
		(property "Reference" "U44"
			(at 36.83 33.02 0)
			(effects
				(font
					(size 1.27 1.27)
				)
			)
		)
		(property "Value" "NCP718BSN330T1G"
			(at 36.83 35.56 0)
			(effects
				(font
					(size 1.27 1.27)
					(thickness 0.15)
				)
			)
		)
		(property "Footprint" "antmicro-footprints:SOT-23-5"
			(at 62.23 48.26 0)
			(effects
				(font
					(size 1.27 1.27)
					(thickness 0.15)
				)
				(justify left bottom)
				(hide yes)
			)
		)
		(property "Datasheet" "https://www.mouser.com/datasheet/2/308/NCP718_D-1224359.pdf"
			(at 62.23 50.8 0)
			(effects
				(font
					(size 1.27 1.27)
					(thickness 0.15)
				)
				(justify left bottom)
				(hide yes)
			)
		)
		(property "Description" ""
			(at 26.67 39.37 0)
			(effects
				(font
					(size 1.27 1.27)
				)
			)
		)
		(property "MPN" "NCP718BSN330T1G"
			(at 62.23 53.34 0)
			(effects
				(font
					(size 1.27 1.27)
					(thickness 0.15)
				)
				(justify left bottom)
				(hide yes)
			)
		)
		(property "Manufacturer" "ON Semiconductor"
			(at 62.23 55.88 0)
			(effects
				(font
					(size 1.27 1.27)
					(thickness 0.15)
				)
				(justify left bottom)
				(hide yes)
			)
		)
		(property "Author" "Antmicro"
			(at 62.23 58.42 0)
			(effects
				(font
					(size 1.27 1.27)
					(thickness 0.15)
				)
				(justify left bottom)
				(hide yes)
			)
		)
		(property "License" "Apache-2.0"
			(at 62.23 60.96 0)
			(effects
				(font
					(size 1.27 1.27)
					(thickness 0.15)
				)
				(justify left bottom)
				(hide yes)
			)
		)
		(pin "1"
		)
		(pin "2"
		)
		(pin "3"
		)
		(pin "4"
		)
		(pin "5"
		)
		(instances
			(project "k410t-devboard"
				(path ""
					(reference "U44")
					(unit 1)
				)
			)
		)
	)
	(symbol
		(lib_id "antmicropower:+1V2_MGTAVTT")
		(at 384.81 107.95 0)
		(unit 1)
		(exclude_from_sim no)
		(in_bom yes)
		(on_board yes)
		(dnp no)
		(fields_autoplaced yes)
		(property "Reference" "#PWR0404"
			(at 384.81 111.76 0)
			(effects
				(font
					(size 1.27 1.27)
				)
				(hide yes)
			)
		)
		(property "Value" "+1V2_MGTAVTT"
			(at 384.81 104.14 0)
			(effects
				(font
					(size 1.27 1.27)
				)
			)
		)
		(property "Footprint" ""
			(at 384.81 107.95 0)
			(effects
				(font
					(size 1.27 1.27)
				)
				(hide yes)
			)
		)
		(property "Datasheet" ""
			(at 384.81 107.95 0)
			(effects
				(font
					(size 1.27 1.27)
				)
				(hide yes)
			)
		)
		(property "Description" ""
			(at 384.81 107.95 0)
			(effects
				(font
					(size 1.27 1.27)
				)
			)
		)
		(pin "1"
		)
		(instances
			(project "k410t-devboard"
				(path ""
					(reference "#PWR0404")
					(unit 1)
				)
			)
		)
	)
	(symbol
		(lib_id "antmicropower:GND")
		(at 69.85 148.59 0)
		(unit 1)
		(exclude_from_sim no)
		(in_bom yes)
		(on_board yes)
		(dnp no)
		(fields_autoplaced yes)
		(property "Reference" "#PWR0367"
			(at 69.85 154.94 0)
			(effects
				(font
					(size 1.27 1.27)
				)
				(hide yes)
			)
		)
		(property "Value" "GND"
			(at 69.85 152.4 0)
			(effects
				(font
					(size 1.27 1.27)
				)
			)
		)
		(property "Footprint" ""
			(at 78.74 156.21 0)
			(effects
				(font
					(size 1.27 1.27)
					(thickness 0.15)
				)
				(justify left bottom)
				(hide yes)
			)
		)
		(property "Datasheet" ""
			(at 78.74 161.29 0)
			(effects
				(font
					(size 1.27 1.27)
					(thickness 0.15)
				)
				(justify left bottom)
				(hide yes)
			)
		)
		(property "Description" ""
			(at 69.85 148.59 0)
			(effects
				(font
					(size 1.27 1.27)
				)
			)
		)
		(property "Author" "Antmicro"
			(at 78.74 156.21 0)
			(effects
				(font
					(size 1.27 1.27)
					(thickness 0.15)
				)
				(justify left bottom)
				(hide yes)
			)
		)
		(property "License" "Apache-2.0"
			(at 78.74 158.75 0)
			(effects
				(font
					(size 1.27 1.27)
					(thickness 0.15)
				)
				(justify left bottom)
				(hide yes)
			)
		)
		(pin "1"
		)
		(instances
			(project "k410t-devboard"
				(path ""
					(reference "#PWR0367")
					(unit 1)
				)
			)
		)
	)
	(symbol
		(lib_id "antmicroResistors0402:R_47k_0402")
		(at 105.41 64.77 0)
		(unit 1)
		(exclude_from_sim no)
		(in_bom yes)
		(on_board yes)
		(dnp no)
		(property "Reference" "R284"
			(at 113.03 63.5 0)
			(effects
				(font
					(size 1.27 1.27)
				)
			)
		)
		(property "Value" "R_47k_0402"
			(at 125.73 77.47 0)
			(effects
				(font
					(size 1.27 1.27)
					(thickness 0.15)
				)
				(justify left bottom)
				(hide yes)
			)
		)
		(property "Footprint" "antmicro-footprints:R_0402_1005Metric"
			(at 125.73 80.01 0)
			(effects
				(font
					(size 1.27 1.27)
					(thickness 0.15)
				)
				(justify left bottom)
				(hide yes)
			)
		)
		(property "Datasheet" "https://www.bourns.com/docs/product-datasheets/cr.pdf"
			(at 125.73 82.55 0)
			(effects
				(font
					(size 1.27 1.27)
					(thickness 0.15)
				)
				(justify left bottom)
				(hide yes)
			)
		)
		(property "Description" ""
			(at 105.41 64.77 0)
			(effects
				(font
					(size 1.27 1.27)
				)
			)
		)
		(property "Manufacturer" "Bourns"
			(at 125.73 87.63 0)
			(effects
				(font
					(size 1.27 1.27)
					(thickness 0.15)
				)
				(justify left bottom)
				(hide yes)
			)
		)
		(property "MPN" "CR0402-FX-4702GLF"
			(at 125.73 85.09 0)
			(effects
				(font
					(size 1.27 1.27)
					(thickness 0.15)
				)
				(justify left bottom)
				(hide yes)
			)
		)
		(property "Val" "47k"
			(at 103.505 63.5 0)
			(effects
				(font
					(size 1.27 1.27)
					(thickness 0.15)
				)
			)
		)
		(property "License" "Apache-2.0"
			(at 125.73 90.17 0)
			(effects
				(font
					(size 1.27 1.27)
					(thickness 0.15)
				)
				(justify left bottom)
				(hide yes)
			)
		)
		(property "Author" "Antmicro"
			(at 125.73 92.71 0)
			(effects
				(font
					(size 1.27 1.27)
					(thickness 0.15)
				)
				(justify left bottom)
				(hide yes)
			)
		)
		(property "Tolerance" "1%"
			(at 125.73 74.93 0)
			(effects
				(font
					(size 1.27 1.27)
				)
				(justify left bottom)
				(hide yes)
			)
		)
		(pin "1"
		)
		(pin "2"
		)
		(instances
			(project "k410t-devboard"
				(path ""
					(reference "R284")
					(unit 1)
				)
			)
		)
	)
	(symbol
		(lib_id "antmicroResistors0603:R_0R_22.4A_0603")
		(at 124.46 182.88 0)
		(unit 1)
		(exclude_from_sim no)
		(in_bom yes)
		(on_board yes)
		(dnp no)
		(property "Reference" "R289"
			(at 127 175.26 0)
			(effects
				(font
					(size 1.27 1.27)
				)
			)
		)
		(property "Value" "R_0R_22.4A_0603"
			(at 147.32 190.5 0)
			(effects
				(font
					(size 1.27 1.27)
					(thickness 0.15)
				)
				(justify left bottom)
				(hide yes)
			)
		)
		(property "Footprint" "antmicro-footprints:R_0603_1608Metric"
			(at 147.32 195.58 0)
			(effects
				(font
					(size 1.27 1.27)
					(thickness 0.15)
				)
				(justify left bottom)
				(hide yes)
			)
		)
		(property "Datasheet" "https://fscdn.rohm.com/en/products/databook/datasheet/passive/resistor/chip_resistor/pmr-jpw-e.pdf"
			(at 147.32 198.12 0)
			(effects
				(font
					(size 1.27 1.27)
					(thickness 0.15)
				)
				(justify left bottom)
				(hide yes)
			)
		)
		(property "Description" ""
			(at 124.46 182.88 0)
			(effects
				(font
					(size 1.27 1.27)
				)
			)
		)
		(property "Manufacturer" "ROHM Semiconductor"
			(at 147.32 200.66 0)
			(effects
				(font
					(size 1.27 1.27)
					(thickness 0.15)
				)
				(justify left bottom)
				(hide yes)
			)
		)
		(property "MPN" "PMR03EZPJ000"
			(at 147.32 203.2 0)
			(effects
				(font
					(size 1.27 1.27)
					(thickness 0.15)
				)
				(justify left bottom)
				(hide yes)
			)
		)
		(property "Val" "0R"
			(at 127 177.8 0)
			(effects
				(font
					(size 1.27 1.27)
					(thickness 0.15)
				)
			)
		)
		(property "Author" "Antmicro"
			(at 147.32 205.74 0)
			(effects
				(font
					(size 1.27 1.27)
					(thickness 0.15)
				)
				(justify left bottom)
				(hide yes)
			)
		)
		(property "License" "Apache-2.0"
			(at 147.32 208.28 0)
			(effects
				(font
					(size 1.27 1.27)
					(thickness 0.15)
				)
				(justify left bottom)
				(hide yes)
			)
		)
		(property "Max. Curr." "22.4A"
			(at 127 180.34 0)
			(effects
				(font
					(size 1.27 1.27)
					(thickness 0.15)
				)
			)
		)
		(property "Tolerance" "template_tolerance"
			(at 144.78 193.04 0)
			(effects
				(font
					(size 1.27 1.27)
				)
				(justify left bottom)
				(hide yes)
			)
		)
		(pin "1"
		)
		(pin "2"
		)
		(instances
			(project "k410t-devboard"
				(path ""
					(reference "R289")
					(unit 1)
				)
			)
		)
	)
	(symbol
		(lib_id "antmicropower:VDC")
		(at 21.59 38.1 0)
		(unit 1)
		(exclude_from_sim no)
		(in_bom yes)
		(on_board yes)
		(dnp no)
		(property "Reference" "#PWR0329"
			(at 21.59 40.64 0)
			(effects
				(font
					(size 1.27 1.27)
				)
				(hide yes)
			)
		)
		(property "Value" "VDC"
			(at 21.59 34.29 0)
			(effects
				(font
					(size 1.27 1.27)
				)
			)
		)
		(property "Footprint" ""
			(at 21.59 38.1 0)
			(effects
				(font
					(size 1.27 1.27)
				)
				(hide yes)
			)
		)
		(property "Datasheet" ""
			(at 21.59 38.1 0)
			(effects
				(font
					(size 1.27 1.27)
				)
				(hide yes)
			)
		)
		(property "Description" ""
			(at 21.59 38.1 0)
			(effects
				(font
					(size 1.27 1.27)
				)
			)
		)
		(pin "1"
		)
		(instances
			(project "k410t-devboard"
				(path ""
					(reference "#PWR0329")
					(unit 1)
				)
			)
		)
	)
	(symbol
		(lib_id "antmicroCapacitors0402:C_100n_0402")
		(at 124.46 24.13 90)
		(unit 1)
		(exclude_from_sim no)
		(in_bom yes)
		(on_board yes)
		(dnp no)
		(property "Reference" "C336"
			(at 125.73 19.685 90)
			(effects
				(font
					(size 1.27 1.27)
				)
				(justify right)
			)
		)
		(property "Value" "C_100n_0402"
			(at 134.62 3.81 0)
			(effects
				(font
					(size 1.27 1.27)
					(thickness 0.15)
				)
				(justify left bottom)
				(hide yes)
			)
		)
		(property "Footprint" "antmicro-footprints:C_0402_1005Metric"
			(at 137.16 3.81 0)
			(effects
				(font
					(size 1.27 1.27)
					(thickness 0.15)
				)
				(justify left bottom)
				(hide yes)
			)
		)
		(property "Datasheet" "https://www.murata.com/products/productdetail?partno=GRM155R61H104KE14%23"
			(at 139.7 3.81 0)
			(effects
				(font
					(size 1.27 1.27)
					(thickness 0.15)
				)
				(justify left bottom)
				(hide yes)
			)
		)
		(property "Description" ""
			(at 124.46 24.13 0)
			(effects
				(font
					(size 1.27 1.27)
				)
			)
		)
		(property "Manufacturer" "Murata"
			(at 144.78 3.81 0)
			(effects
				(font
					(size 1.27 1.27)
					(thickness 0.15)
				)
				(justify left bottom)
				(hide yes)
			)
		)
		(property "MPN" "GRM155R61H104KE14D"
			(at 142.24 3.81 0)
			(effects
				(font
					(size 1.27 1.27)
					(thickness 0.15)
				)
				(justify left bottom)
				(hide yes)
			)
		)
		(property "Val" "100n"
			(at 125.73 23.495 90)
			(effects
				(font
					(size 1.27 1.27)
					(thickness 0.15)
				)
				(justify right)
			)
		)
		(property "License" "Apache-2.0"
			(at 147.32 3.81 0)
			(effects
				(font
					(size 1.27 1.27)
					(thickness 0.15)
				)
				(justify left bottom)
				(hide yes)
			)
		)
		(property "Author" "Antmicro"
			(at 149.86 3.81 0)
			(effects
				(font
					(size 1.27 1.27)
					(thickness 0.15)
				)
				(justify left bottom)
				(hide yes)
			)
		)
		(property "Voltage" "50V"
			(at 152.4 3.81 0)
			(effects
				(font
					(size 1.27 1.27)
				)
				(justify left bottom)
				(hide yes)
			)
		)
		(property "Dielectric" "X5R"
			(at 154.94 3.81 0)
			(effects
				(font
					(size 1.27 1.27)
				)
				(justify left bottom)
				(hide yes)
			)
		)
		(pin "1"
		)
		(pin "2"
		)
		(instances
			(project "k410t-devboard"
				(path ""
					(reference "C336")
					(unit 1)
				)
			)
		)
	)
	(symbol
		(lib_id "antmicropower:GND")
		(at 154.94 25.4 0)
		(unit 1)
		(exclude_from_sim no)
		(in_bom yes)
		(on_board yes)
		(dnp no)
		(property "Reference" "#PWR0394"
			(at 154.94 31.75 0)
			(effects
				(font
					(size 1.27 1.27)
				)
				(hide yes)
			)
		)
		(property "Value" "GND"
			(at 151.13 26.67 0)
			(effects
				(font
					(size 1.27 1.27)
				)
			)
		)
		(property "Footprint" ""
			(at 163.83 33.02 0)
			(effects
				(font
					(size 1.27 1.27)
					(thickness 0.15)
				)
				(justify left bottom)
				(hide yes)
			)
		)
		(property "Datasheet" ""
			(at 163.83 38.1 0)
			(effects
				(font
					(size 1.27 1.27)
					(thickness 0.15)
				)
				(justify left bottom)
				(hide yes)
			)
		)
		(property "Description" ""
			(at 154.94 25.4 0)
			(effects
				(font
					(size 1.27 1.27)
				)
			)
		)
		(property "Author" "Antmicro"
			(at 163.83 33.02 0)
			(effects
				(font
					(size 1.27 1.27)
					(thickness 0.15)
				)
				(justify left bottom)
				(hide yes)
			)
		)
		(property "License" "Apache-2.0"
			(at 163.83 35.56 0)
			(effects
				(font
					(size 1.27 1.27)
					(thickness 0.15)
				)
				(justify left bottom)
				(hide yes)
			)
		)
		(pin "1"
		)
		(instances
			(project "k410t-devboard"
				(path ""
					(reference "#PWR0394")
					(unit 1)
				)
			)
		)
	)
	(symbol
		(lib_id "antmicroResistors0603:R_0R_22.4A_0603")
		(at 363.22 111.76 0)
		(unit 1)
		(exclude_from_sim no)
		(in_bom yes)
		(on_board yes)
		(dnp no)
		(fields_autoplaced yes)
		(property "Reference" "R326"
			(at 365.76 102.87 0)
			(effects
				(font
					(size 1.27 1.27)
				)
			)
		)
		(property "Value" "R_0R_22.4A_0603"
			(at 386.08 119.38 0)
			(effects
				(font
					(size 1.27 1.27)
					(thickness 0.15)
				)
				(justify left bottom)
				(hide yes)
			)
		)
		(property "Footprint" "antmicro-footprints:R_0603_1608Metric"
			(at 386.08 124.46 0)
			(effects
				(font
					(size 1.27 1.27)
					(thickness 0.15)
				)
				(justify left bottom)
				(hide yes)
			)
		)
		(property "Datasheet" "https://fscdn.rohm.com/en/products/databook/datasheet/passive/resistor/chip_resistor/pmr-jpw-e.pdf"
			(at 386.08 127 0)
			(effects
				(font
					(size 1.27 1.27)
					(thickness 0.15)
				)
				(justify left bottom)
				(hide yes)
			)
		)
		(property "Description" ""
			(at 363.22 111.76 0)
			(effects
				(font
					(size 1.27 1.27)
				)
			)
		)
		(property "Manufacturer" "ROHM Semiconductor"
			(at 386.08 129.54 0)
			(effects
				(font
					(size 1.27 1.27)
					(thickness 0.15)
				)
				(justify left bottom)
				(hide yes)
			)
		)
		(property "MPN" "PMR03EZPJ000"
			(at 386.08 132.08 0)
			(effects
				(font
					(size 1.27 1.27)
					(thickness 0.15)
				)
				(justify left bottom)
				(hide yes)
			)
		)
		(property "Val" "0R"
			(at 365.76 105.41 0)
			(effects
				(font
					(size 1.27 1.27)
					(thickness 0.15)
				)
			)
		)
		(property "Author" "Antmicro"
			(at 386.08 134.62 0)
			(effects
				(font
					(size 1.27 1.27)
					(thickness 0.15)
				)
				(justify left bottom)
				(hide yes)
			)
		)
		(property "License" "Apache-2.0"
			(at 386.08 137.16 0)
			(effects
				(font
					(size 1.27 1.27)
					(thickness 0.15)
				)
				(justify left bottom)
				(hide yes)
			)
		)
		(property "Max. Curr." "22.4A"
			(at 365.76 107.95 0)
			(effects
				(font
					(size 1.27 1.27)
					(thickness 0.15)
				)
			)
		)
		(property "Tolerance" "template_tolerance"
			(at 383.54 121.92 0)
			(effects
				(font
					(size 1.27 1.27)
				)
				(justify left bottom)
				(hide yes)
			)
		)
		(pin "1"
		)
		(pin "2"
		)
		(instances
			(project "k410t-devboard"
				(path ""
					(reference "R326")
					(unit 1)
				)
			)
		)
	)
	(symbol
		(lib_id "k410t-devboard:Net-Tie_2")
		(at 256.54 186.69 90)
		(unit 1)
		(exclude_from_sim no)
		(in_bom yes)
		(on_board yes)
		(dnp no)
		(fields_autoplaced yes)
		(property "Reference" "NT26"
			(at 255.27 186.69 0)
			(effects
				(font
					(size 1.27 1.27)
				)
				(hide yes)
			)
		)
		(property "Value" "Net-Tie_2"
			(at 258.445 184.7849 90)
			(effects
				(font
					(size 1.27 1.27)
					(thickness 0.15)
				)
				(justify right)
				(hide yes)
			)
		)
		(property "Footprint" "antmicro-footprints:NetTie-2_SMD_Pad0.127mm"
			(at 261.62 165.1 0)
			(effects
				(font
					(size 1.27 1.27)
					(thickness 0.15)
				)
				(justify left bottom)
				(hide yes)
			)
		)
		(property "Datasheet" ""
			(at 264.16 165.1 0)
			(effects
				(font
					(size 1.27 1.27)
					(thickness 0.15)
				)
				(justify left bottom)
				(hide yes)
			)
		)
		(property "Description" ""
			(at 256.54 186.69 0)
			(effects
				(font
					(size 1.27 1.27)
				)
			)
		)
		(property "MPN" ""
			(at 265.43 165.1 0)
			(effects
				(font
					(size 1.27 1.27)
				)
				(justify left)
				(hide yes)
			)
		)
		(property "Manufacturer" ""
			(at 267.97 165.1 0)
			(effects
				(font
					(size 1.27 1.27)
				)
				(justify left)
				(hide yes)
			)
		)
		(property "Author" "Antmicro"
			(at 271.78 165.1 0)
			(effects
				(font
					(size 1.27 1.27)
					(thickness 0.15)
				)
				(justify left bottom)
				(hide yes)
			)
		)
		(property "License" "Apache-2.0"
			(at 274.32 165.1 0)
			(effects
				(font
					(size 1.27 1.27)
					(thickness 0.15)
				)
				(justify left bottom)
				(hide yes)
			)
		)
		(pin "1"
		)
		(pin "2"
		)
		(instances
			(project "k410t-devboard"
				(path ""
					(reference "NT26")
					(unit 1)
				)
			)
		)
	)
	(symbol
		(lib_id "antmicroTestPoints:TP_0.75mm_SMD")
		(at 68.58 146.05 180)
		(unit 1)
		(exclude_from_sim no)
		(in_bom yes)
		(on_board yes)
		(dnp no)
		(fields_autoplaced yes)
		(property "Reference" "TP4"
			(at 63.5 146.05 0)
			(effects
				(font
					(size 1.27 1.27)
				)
				(justify left)
			)
		)
		(property "Value" "TP_0.75mm_SMD"
			(at 68.58 143.51 0)
			(effects
				(font
					(size 1.27 1.27)
				)
				(hide yes)
			)
		)
		(property "Footprint" "antmicro-footprints:TP_SMD_0.75mm"
			(at 63.5 151.13 0)
			(effects
				(font
					(size 1.27 1.27)
				)
				(justify left)
				(hide yes)
			)
		)
		(property "Datasheet" ""
			(at 63.5 153.67 0)
			(effects
				(font
					(size 1.27 1.27)
				)
				(justify left)
				(hide yes)
			)
		)
		(property "Description" ""
			(at 68.58 146.05 0)
			(effects
				(font
					(size 1.27 1.27)
				)
			)
		)
		(property "MPN" ""
			(at 68.58 146.05 0)
			(effects
				(font
					(size 1.27 1.27)
				)
				(hide yes)
			)
		)
		(property "Manufacturer" ""
			(at 68.58 146.05 0)
			(effects
				(font
					(size 1.27 1.27)
				)
				(hide yes)
			)
		)
		(property "Author" "Antmicro"
			(at 53.34 130.81 0)
			(effects
				(font
					(size 1.27 1.27)
					(thickness 0.15)
				)
				(justify left bottom)
				(hide yes)
			)
		)
		(property "License" "Apache-2.0"
			(at 53.34 128.27 0)
			(effects
				(font
					(size 1.27 1.27)
					(thickness 0.15)
				)
				(justify left bottom)
				(hide yes)
			)
		)
		(pin "1"
		)
		(instances
			(project "k410t-devboard"
				(path ""
					(reference "TP4")
					(unit 1)
				)
			)
		)
	)
	(symbol
		(lib_id "antmicroCapacitors0402:C_1u_0402")
		(at 49.53 209.55 90)
		(unit 1)
		(exclude_from_sim no)
		(in_bom yes)
		(on_board yes)
		(dnp no)
		(fields_autoplaced yes)
		(property "Reference" "C318"
			(at 52.07 205.7335 90)
			(effects
				(font
					(size 1.27 1.27)
				)
				(justify right)
			)
		)
		(property "Value" "C_1u_0402"
			(at 53.34 209.55 0)
			(effects
				(font
					(size 1.27 1.27)
				)
				(hide yes)
			)
		)
		(property "Footprint" "antmicro-footprints:C_0402_1005Metric"
			(at 44.45 204.47 0)
			(effects
				(font
					(size 1.27 1.27)
				)
				(justify left)
				(hide yes)
			)
		)
		(property "Datasheet" "https://product.tdk.com/en/search/capacitor/ceramic/mlcc/info?part_no=C1005X6S1A105K050BC"
			(at 49.53 209.55 0)
			(effects
				(font
					(size 1.27 1.27)
				)
				(hide yes)
			)
		)
		(property "Description" ""
			(at 49.53 209.55 0)
			(effects
				(font
					(size 1.27 1.27)
				)
			)
		)
		(property "Manufacturer" "TDK"
			(at 39.37 204.47 0)
			(effects
				(font
					(size 1.27 1.27)
				)
				(justify left)
				(hide yes)
			)
		)
		(property "MPN" "C1005X6S1A105K050BC"
			(at 41.91 204.47 0)
			(effects
				(font
					(size 1.27 1.27)
				)
				(justify left)
				(hide yes)
			)
		)
		(property "Val" "1u"
			(at 52.07 208.2735 90)
			(effects
				(font
					(size 1.27 1.27)
				)
				(justify right)
			)
		)
		(property "License" "Apache-2.0"
			(at 72.39 189.23 0)
			(effects
				(font
					(size 1.27 1.27)
					(thickness 0.15)
				)
				(justify left bottom)
				(hide yes)
			)
		)
		(property "Author" "Antmicro"
			(at 74.93 189.23 0)
			(effects
				(font
					(size 1.27 1.27)
					(thickness 0.15)
				)
				(justify left bottom)
				(hide yes)
			)
		)
		(property "Voltage" ""
			(at 77.47 189.23 0)
			(effects
				(font
					(size 1.27 1.27)
				)
				(justify left bottom)
				(hide yes)
			)
		)
		(property "Dielectric" ""
			(at 80.01 189.23 0)
			(effects
				(font
					(size 1.27 1.27)
				)
				(justify left bottom)
				(hide yes)
			)
		)
		(pin "1"
		)
		(pin "2"
		)
		(instances
			(project "k410t-devboard"
				(path ""
					(reference "C318")
					(unit 1)
				)
			)
		)
	)
	(symbol
		(lib_id "antmicropower:+3.3V")
		(at 133.35 181.61 0)
		(unit 1)
		(exclude_from_sim no)
		(in_bom yes)
		(on_board yes)
		(dnp no)
		(fields_autoplaced yes)
		(property "Reference" "#PWR0353"
			(at 133.35 185.42 0)
			(effects
				(font
					(size 1.27 1.27)
				)
				(hide yes)
			)
		)
		(property "Value" "+3V3"
			(at 133.35 178.054 0)
			(effects
				(font
					(size 1.27 1.27)
				)
			)
		)
		(property "Footprint" ""
			(at 133.35 181.61 0)
			(effects
				(font
					(size 1.27 1.27)
				)
				(hide yes)
			)
		)
		(property "Datasheet" ""
			(at 133.35 181.61 0)
			(effects
				(font
					(size 1.27 1.27)
				)
				(hide yes)
			)
		)
		(property "Description" ""
			(at 133.35 181.61 0)
			(effects
				(font
					(size 1.27 1.27)
				)
			)
		)
		(pin "1"
		)
		(instances
			(project "k410t-devboard"
				(path ""
					(reference "#PWR0353")
					(unit 1)
				)
			)
		)
	)
	(symbol
		(lib_id "antmicroCapacitorsmisc:C_22u_25V_0805")
		(at 293.37 36.83 90)
		(unit 1)
		(exclude_from_sim no)
		(in_bom yes)
		(on_board yes)
		(dnp no)
		(fields_autoplaced yes)
		(property "Reference" "C345"
			(at 295.91 31.7436 90)
			(effects
				(font
					(size 1.27 1.27)
				)
				(justify right)
			)
		)
		(property "Value" "C_22u_25V_0805"
			(at 303.53 16.51 0)
			(effects
				(font
					(size 1.27 1.27)
					(thickness 0.15)
				)
				(justify left bottom)
				(hide yes)
			)
		)
		(property "Footprint" "antmicro-footprints:C_0805_2012Metric"
			(at 306.07 16.51 0)
			(effects
				(font
					(size 1.27 1.27)
					(thickness 0.15)
				)
				(justify left bottom)
				(hide yes)
			)
		)
		(property "Datasheet" "https://product.samsungsem.com/mlcc/CL21A226MAYNNN.do"
			(at 308.61 16.51 0)
			(effects
				(font
					(size 1.27 1.27)
					(thickness 0.15)
				)
				(justify left bottom)
				(hide yes)
			)
		)
		(property "Description" ""
			(at 293.37 36.83 0)
			(effects
				(font
					(size 1.27 1.27)
				)
			)
		)
		(property "Manufacturer" "Samsung Electro-Mechanics"
			(at 313.69 16.51 0)
			(effects
				(font
					(size 1.27 1.27)
					(thickness 0.15)
				)
				(justify left bottom)
				(hide yes)
			)
		)
		(property "MPN" "CL21A226MAYNNNE"
			(at 311.15 16.51 0)
			(effects
				(font
					(size 1.27 1.27)
					(thickness 0.15)
				)
				(justify left bottom)
				(hide yes)
			)
		)
		(property "Val" "22u"
			(at 295.91 34.2836 90)
			(effects
				(font
					(size 1.27 1.27)
					(thickness 0.15)
				)
				(justify right)
			)
		)
		(property "License" "Apache-2.0"
			(at 316.23 16.51 0)
			(effects
				(font
					(size 1.27 1.27)
					(thickness 0.15)
				)
				(justify left bottom)
				(hide yes)
			)
		)
		(property "Author" "Antmicro"
			(at 318.77 16.51 0)
			(effects
				(font
					(size 1.27 1.27)
					(thickness 0.15)
				)
				(justify left bottom)
				(hide yes)
			)
		)
		(property "Voltage" "25V"
			(at 295.91 36.8236 90)
			(effects
				(font
					(size 1.27 1.27)
				)
				(justify right)
			)
		)
		(property "Dielectric" "X5R"
			(at 323.85 16.51 0)
			(effects
				(font
					(size 1.27 1.27)
				)
				(justify left bottom)
				(hide yes)
			)
		)
		(pin "1"
		)
		(pin "2"
		)
		(instances
			(project "k410t-devboard"
				(path ""
					(reference "C345")
					(unit 1)
				)
			)
		)
	)
	(symbol
		(lib_id "antmicropower:+1V0_MGTAVCC")
		(at 200.66 86.36 0)
		(unit 1)
		(exclude_from_sim no)
		(in_bom yes)
		(on_board yes)
		(dnp no)
		(fields_autoplaced yes)
		(property "Reference" "#PWR0446"
			(at 200.66 90.17 0)
			(effects
				(font
					(size 1.27 1.27)
				)
				(hide yes)
			)
		)
		(property "Value" "+1V0_MGTAVCC"
			(at 200.66 82.55 0)
			(effects
				(font
					(size 1.27 1.27)
				)
			)
		)
		(property "Footprint" ""
			(at 200.66 86.36 0)
			(effects
				(font
					(size 1.27 1.27)
				)
				(hide yes)
			)
		)
		(property "Datasheet" ""
			(at 200.66 86.36 0)
			(effects
				(font
					(size 1.27 1.27)
				)
				(hide yes)
			)
		)
		(property "Description" ""
			(at 200.66 86.36 0)
			(effects
				(font
					(size 1.27 1.27)
				)
			)
		)
		(pin "1"
		)
		(instances
			(project "k410t-devboard"
				(path ""
					(reference "#PWR0446")
					(unit 1)
				)
			)
		)
	)
	(symbol
		(lib_id "antmicropower:+1V8")
		(at 201.93 127 0)
		(unit 1)
		(exclude_from_sim no)
		(in_bom yes)
		(on_board yes)
		(dnp no)
		(fields_autoplaced yes)
		(property "Reference" "#PWR0369"
			(at 201.93 130.81 0)
			(effects
				(font
					(size 1.27 1.27)
				)
				(hide yes)
			)
		)
		(property "Value" "+1V8"
			(at 201.93 123.444 0)
			(effects
				(font
					(size 1.27 1.27)
				)
			)
		)
		(property "Footprint" ""
			(at 217.17 134.62 0)
			(effects
				(font
					(size 1.27 1.27)
					(thickness 0.15)
				)
				(justify left bottom)
				(hide yes)
			)
		)
		(property "Datasheet" ""
			(at 217.17 137.16 0)
			(effects
				(font
					(size 1.27 1.27)
					(thickness 0.15)
				)
				(justify left bottom)
				(hide yes)
			)
		)
		(property "Description" ""
			(at 201.93 127 0)
			(effects
				(font
					(size 1.27 1.27)
				)
			)
		)
		(property "Author" "Antmicro"
			(at 217.17 134.62 0)
			(effects
				(font
					(size 1.27 1.27)
					(thickness 0.15)
				)
				(justify left bottom)
				(hide yes)
			)
		)
		(property "License" "Apache-2.0"
			(at 217.17 137.16 0)
			(effects
				(font
					(size 1.27 1.27)
					(thickness 0.15)
				)
				(justify left bottom)
				(hide yes)
			)
		)
		(pin "1"
		)
		(instances
			(project "k410t-devboard"
				(path ""
					(reference "#PWR0369")
					(unit 1)
				)
			)
		)
	)
	(symbol
		(lib_id "antmicropower:GND")
		(at 355.6 245.11 0)
		(unit 1)
		(exclude_from_sim no)
		(in_bom yes)
		(on_board yes)
		(dnp no)
		(fields_autoplaced yes)
		(property "Reference" "#PWR0449"
			(at 355.6 251.46 0)
			(effects
				(font
					(size 1.27 1.27)
				)
				(hide yes)
			)
		)
		(property "Value" "GND"
			(at 355.6 248.92 0)
			(effects
				(font
					(size 1.27 1.27)
				)
			)
		)
		(property "Footprint" ""
			(at 364.49 252.73 0)
			(effects
				(font
					(size 1.27 1.27)
					(thickness 0.15)
				)
				(justify left bottom)
				(hide yes)
			)
		)
		(property "Datasheet" ""
			(at 364.49 257.81 0)
			(effects
				(font
					(size 1.27 1.27)
					(thickness 0.15)
				)
				(justify left bottom)
				(hide yes)
			)
		)
		(property "Description" ""
			(at 355.6 245.11 0)
			(effects
				(font
					(size 1.27 1.27)
				)
			)
		)
		(property "Author" "Antmicro"
			(at 364.49 252.73 0)
			(effects
				(font
					(size 1.27 1.27)
					(thickness 0.15)
				)
				(justify left bottom)
				(hide yes)
			)
		)
		(property "License" "Apache-2.0"
			(at 364.49 255.27 0)
			(effects
				(font
					(size 1.27 1.27)
					(thickness 0.15)
				)
				(justify left bottom)
				(hide yes)
			)
		)
		(pin "1"
		)
		(instances
			(project "k410t-devboard"
				(path ""
					(reference "#PWR0449")
					(unit 1)
				)
			)
		)
	)
	(symbol
		(lib_id "antmicroResistors0402:R_0R_0402")
		(at 384.81 153.67 180)
		(unit 1)
		(exclude_from_sim no)
		(in_bom yes)
		(on_board yes)
		(dnp no)
		(property "Reference" "R328"
			(at 382.27 149.86 0)
			(effects
				(font
					(size 1.27 1.27)
				)
			)
		)
		(property "Value" "R_0R_0402"
			(at 364.49 140.97 0)
			(effects
				(font
					(size 1.27 1.27)
					(thickness 0.15)
				)
				(justify left bottom)
				(hide yes)
			)
		)
		(property "Footprint" "antmicro-footprints:R_0402_1005Metric"
			(at 364.49 138.43 0)
			(effects
				(font
					(size 1.27 1.27)
					(thickness 0.15)
				)
				(justify left bottom)
				(hide yes)
			)
		)
		(property "Datasheet" "https://industrial.panasonic.com/cdbs/www-data/pdf/RDA0000/AOA0000C301.pdf"
			(at 364.49 135.89 0)
			(effects
				(font
					(size 1.27 1.27)
					(thickness 0.15)
				)
				(justify left bottom)
				(hide yes)
			)
		)
		(property "Description" ""
			(at 384.81 153.67 0)
			(effects
				(font
					(size 1.27 1.27)
				)
			)
		)
		(property "Manufacturer" "Panasonic"
			(at 364.49 130.81 0)
			(effects
				(font
					(size 1.27 1.27)
					(thickness 0.15)
				)
				(justify left bottom)
				(hide yes)
			)
		)
		(property "MPN" "ERJ2GE0R00X"
			(at 364.49 133.35 0)
			(effects
				(font
					(size 1.27 1.27)
					(thickness 0.15)
				)
				(justify left bottom)
				(hide yes)
			)
		)
		(property "Val" "0R"
			(at 382.27 151.765 0)
			(effects
				(font
					(size 1.27 1.27)
					(thickness 0.15)
				)
			)
		)
		(property "License" "Apache-2.0"
			(at 364.49 128.27 0)
			(effects
				(font
					(size 1.27 1.27)
					(thickness 0.15)
				)
				(justify left bottom)
				(hide yes)
			)
		)
		(property "Author" "Antmicro"
			(at 364.49 125.73 0)
			(effects
				(font
					(size 1.27 1.27)
					(thickness 0.15)
				)
				(justify left bottom)
				(hide yes)
			)
		)
		(property "Tolerance" "~"
			(at 364.49 143.51 0)
			(effects
				(font
					(size 1.27 1.27)
				)
				(justify left bottom)
				(hide yes)
			)
		)
		(property "Current" "1A"
			(at 382.27 150.495 0)
			(effects
				(font
					(size 1.27 1.27)
					(thickness 0.15)
				)
				(hide yes)
			)
		)
		(pin "1"
		)
		(pin "2"
		)
		(instances
			(project "k410t-devboard"
				(path ""
					(reference "R328")
					(unit 1)
				)
			)
		)
	)
	(symbol
		(lib_id "antmicroResistors0402:R_0R_0402")
		(at 176.53 240.03 90)
		(unit 1)
		(exclude_from_sim no)
		(in_bom no)
		(on_board yes)
		(dnp yes)
		(property "Reference" "R295"
			(at 179.07 236.22 90)
			(effects
				(font
					(size 1.27 1.27)
				)
				(justify right)
			)
		)
		(property "Value" "R_0R_0402"
			(at 189.23 219.71 0)
			(effects
				(font
					(size 1.27 1.27)
					(thickness 0.15)
				)
				(justify left bottom)
				(hide yes)
			)
		)
		(property "Footprint" "antmicro-footprints:R_0402_1005Metric"
			(at 191.77 219.71 0)
			(effects
				(font
					(size 1.27 1.27)
					(thickness 0.15)
				)
				(justify left bottom)
				(hide yes)
			)
		)
		(property "Datasheet" "https://industrial.panasonic.com/cdbs/www-data/pdf/RDA0000/AOA0000C301.pdf"
			(at 194.31 219.71 0)
			(effects
				(font
					(size 1.27 1.27)
					(thickness 0.15)
				)
				(justify left bottom)
				(hide yes)
			)
		)
		(property "Description" ""
			(at 176.53 240.03 0)
			(effects
				(font
					(size 1.27 1.27)
				)
			)
		)
		(property "Manufacturer" "Panasonic"
			(at 199.39 219.71 0)
			(effects
				(font
					(size 1.27 1.27)
					(thickness 0.15)
				)
				(justify left bottom)
				(hide yes)
			)
		)
		(property "MPN" "ERJ2GE0R00X"
			(at 196.85 219.71 0)
			(effects
				(font
					(size 1.27 1.27)
					(thickness 0.15)
				)
				(justify left bottom)
				(hide yes)
			)
		)
		(property "Val" "0R"
			(at 179.07 238.76 90)
			(effects
				(font
					(size 1.27 1.27)
					(thickness 0.15)
				)
				(justify right)
			)
		)
		(property "DNP" "DNP"
			(at 176.53 235.585 0)
			(effects
				(font
					(size 1.27 1.27)
				)
				(justify right)
			)
		)
		(property "License" "Apache-2.0"
			(at 201.93 219.71 0)
			(effects
				(font
					(size 1.27 1.27)
					(thickness 0.15)
				)
				(justify left bottom)
				(hide yes)
			)
		)
		(property "Author" "Antmicro"
			(at 204.47 219.71 0)
			(effects
				(font
					(size 1.27 1.27)
					(thickness 0.15)
				)
				(justify left bottom)
				(hide yes)
			)
		)
		(property "Tolerance" "~"
			(at 186.69 219.71 0)
			(effects
				(font
					(size 1.27 1.27)
				)
				(justify left bottom)
				(hide yes)
			)
		)
		(property "Current" "1A"
			(at 179.07 241.2999 90)
			(effects
				(font
					(size 1.27 1.27)
					(thickness 0.15)
				)
				(justify right)
				(hide yes)
			)
		)
		(pin "1"
		)
		(pin "2"
		)
		(instances
			(project "k410t-devboard"
				(path ""
					(reference "R295")
					(unit 1)
				)
			)
		)
	)
	(symbol
		(lib_id "antmicropower:GND")
		(at 49.53 191.77 0)
		(unit 1)
		(exclude_from_sim no)
		(in_bom yes)
		(on_board yes)
		(dnp no)
		(property "Reference" "#PWR0363"
			(at 49.53 198.12 0)
			(effects
				(font
					(size 1.27 1.27)
				)
				(hide yes)
			)
		)
		(property "Value" "GND"
			(at 49.53 195.58 0)
			(effects
				(font
					(size 1.27 1.27)
				)
			)
		)
		(property "Footprint" ""
			(at 58.42 199.39 0)
			(effects
				(font
					(size 1.27 1.27)
					(thickness 0.15)
				)
				(justify left bottom)
				(hide yes)
			)
		)
		(property "Datasheet" ""
			(at 58.42 204.47 0)
			(effects
				(font
					(size 1.27 1.27)
					(thickness 0.15)
				)
				(justify left bottom)
				(hide yes)
			)
		)
		(property "Description" ""
			(at 49.53 191.77 0)
			(effects
				(font
					(size 1.27 1.27)
				)
			)
		)
		(property "Author" "Antmicro"
			(at 58.42 199.39 0)
			(effects
				(font
					(size 1.27 1.27)
					(thickness 0.15)
				)
				(justify left bottom)
				(hide yes)
			)
		)
		(property "License" "Apache-2.0"
			(at 58.42 201.93 0)
			(effects
				(font
					(size 1.27 1.27)
					(thickness 0.15)
				)
				(justify left bottom)
				(hide yes)
			)
		)
		(pin "1"
		)
		(instances
			(project "k410t-devboard"
				(path ""
					(reference "#PWR0363")
					(unit 1)
				)
			)
		)
	)
	(symbol
		(lib_id "antmicropower:GND")
		(at 190.5 261.62 0)
		(unit 1)
		(exclude_from_sim no)
		(in_bom yes)
		(on_board yes)
		(dnp no)
		(fields_autoplaced yes)
		(property "Reference" "#PWR0398"
			(at 190.5 267.97 0)
			(effects
				(font
					(size 1.27 1.27)
				)
				(hide yes)
			)
		)
		(property "Value" "GND"
			(at 190.5 265.43 0)
			(effects
				(font
					(size 1.27 1.27)
				)
			)
		)
		(property "Footprint" ""
			(at 199.39 269.24 0)
			(effects
				(font
					(size 1.27 1.27)
					(thickness 0.15)
				)
				(justify left bottom)
				(hide yes)
			)
		)
		(property "Datasheet" ""
			(at 199.39 274.32 0)
			(effects
				(font
					(size 1.27 1.27)
					(thickness 0.15)
				)
				(justify left bottom)
				(hide yes)
			)
		)
		(property "Description" ""
			(at 190.5 261.62 0)
			(effects
				(font
					(size 1.27 1.27)
				)
			)
		)
		(property "Author" "Antmicro"
			(at 199.39 269.24 0)
			(effects
				(font
					(size 1.27 1.27)
					(thickness 0.15)
				)
				(justify left bottom)
				(hide yes)
			)
		)
		(property "License" "Apache-2.0"
			(at 199.39 271.78 0)
			(effects
				(font
					(size 1.27 1.27)
					(thickness 0.15)
				)
				(justify left bottom)
				(hide yes)
			)
		)
		(pin "1"
		)
		(instances
			(project "k410t-devboard"
				(path ""
					(reference "#PWR0398")
					(unit 1)
				)
			)
		)
	)
	(symbol
		(lib_id "antmicroCapacitors0402:C_10u_0402")
		(at 281.94 228.6 90)
		(unit 1)
		(exclude_from_sim no)
		(in_bom yes)
		(on_board yes)
		(dnp no)
		(property "Reference" "C340"
			(at 283.21 224.155 90)
			(effects
				(font
					(size 1.27 1.27)
				)
				(justify right)
			)
		)
		(property "Value" "C_10u_0402"
			(at 292.1 208.28 0)
			(effects
				(font
					(size 1.27 1.27)
					(thickness 0.15)
				)
				(justify left bottom)
				(hide yes)
			)
		)
		(property "Footprint" "antmicro-footprints:C_0402_1005Metric"
			(at 294.64 208.28 0)
			(effects
				(font
					(size 1.27 1.27)
					(thickness 0.15)
				)
				(justify left bottom)
				(hide yes)
			)
		)
		(property "Datasheet" "https://www.yageo.com/en/Chart/Download/pdf/CC0402MRX5R5BB106"
			(at 297.18 208.28 0)
			(effects
				(font
					(size 1.27 1.27)
					(thickness 0.15)
				)
				(justify left bottom)
				(hide yes)
			)
		)
		(property "Description" ""
			(at 281.94 228.6 0)
			(effects
				(font
					(size 1.27 1.27)
				)
			)
		)
		(property "Manufacturer" "YAGEO"
			(at 302.26 208.28 0)
			(effects
				(font
					(size 1.27 1.27)
					(thickness 0.15)
				)
				(justify left bottom)
				(hide yes)
			)
		)
		(property "MPN" "CC0402MRX5R5BB106"
			(at 299.72 208.28 0)
			(effects
				(font
					(size 1.27 1.27)
					(thickness 0.15)
				)
				(justify left bottom)
				(hide yes)
			)
		)
		(property "Val" "10u"
			(at 283.21 227.965 90)
			(effects
				(font
					(size 1.27 1.27)
					(thickness 0.15)
				)
				(justify right)
			)
		)
		(property "License" "Apache-2.0"
			(at 304.8 208.28 0)
			(effects
				(font
					(size 1.27 1.27)
					(thickness 0.15)
				)
				(justify left bottom)
				(hide yes)
			)
		)
		(property "Author" "Antmicro"
			(at 307.34 208.28 0)
			(effects
				(font
					(size 1.27 1.27)
					(thickness 0.15)
				)
				(justify left bottom)
				(hide yes)
			)
		)
		(property "Voltage" ""
			(at 309.88 208.28 0)
			(effects
				(font
					(size 1.27 1.27)
				)
				(justify left bottom)
				(hide yes)
			)
		)
		(property "Dielectric" ""
			(at 312.42 208.28 0)
			(effects
				(font
					(size 1.27 1.27)
				)
				(justify left bottom)
				(hide yes)
			)
		)
		(pin "1"
		)
		(pin "2"
		)
		(instances
			(project "k410t-devboard"
				(path ""
					(reference "C340")
					(unit 1)
				)
			)
		)
	)
	(symbol
		(lib_id "antmicroPMICVoltageRegulatorsLinear:XC6230H001ER-G")
		(at 330.2 111.76 0)
		(unit 1)
		(exclude_from_sim no)
		(in_bom yes)
		(on_board yes)
		(dnp no)
		(fields_autoplaced yes)
		(property "Reference" "U40"
			(at 337.82 104.14 0)
			(effects
				(font
					(size 1.27 1.27)
				)
			)
		)
		(property "Value" "XC6230H001ER-G"
			(at 337.82 107.95 0)
			(effects
				(font
					(size 1.27 1.27)
					(thickness 0.15)
				)
				(hide yes)
			)
		)
		(property "Footprint" "antmicro-footprints:Torex_USP-6C"
			(at 360.68 119.38 0)
			(effects
				(font
					(size 1.27 1.27)
					(thickness 0.15)
				)
				(justify left bottom)
				(hide yes)
			)
		)
		(property "Datasheet" "https://www.torexsemi.com/file/xc6230/XC6230.pdf"
			(at 360.68 121.92 0)
			(effects
				(font
					(size 1.27 1.27)
					(thickness 0.15)
				)
				(justify left bottom)
				(hide yes)
			)
		)
		(property "Description" ""
			(at 330.2 111.76 0)
			(effects
				(font
					(size 1.27 1.27)
				)
			)
		)
		(property "MPN" "XC6230H001ER-G"
			(at 337.82 106.68 0)
			(effects
				(font
					(size 1.27 1.27)
					(thickness 0.15)
				)
			)
		)
		(property "Manufacturer" "Torex Semiconductor"
			(at 360.68 127 0)
			(effects
				(font
					(size 1.27 1.27)
					(thickness 0.15)
				)
				(justify left bottom)
				(hide yes)
			)
		)
		(property "Author" "Antmicro"
			(at 360.68 129.54 0)
			(effects
				(font
					(size 1.27 1.27)
					(thickness 0.15)
				)
				(justify left bottom)
				(hide yes)
			)
		)
		(property "License" "Apache-2.0"
			(at 360.68 132.08 0)
			(effects
				(font
					(size 1.27 1.27)
					(thickness 0.15)
				)
				(justify left bottom)
				(hide yes)
			)
		)
		(pin "1"
		)
		(pin "2"
		)
		(pin "3"
		)
		(pin "4"
		)
		(pin "5"
		)
		(pin "6"
		)
		(pin "7"
		)
		(instances
			(project "k410t-devboard"
				(path ""
					(reference "U40")
					(unit 1)
				)
			)
		)
	)
	(symbol
		(lib_id "antmicroResistors0402:R_0R_0402")
		(at 242.57 246.38 90)
		(unit 1)
		(exclude_from_sim no)
		(in_bom no)
		(on_board yes)
		(dnp yes)
		(property "Reference" "R316"
			(at 244.475 242.57 90)
			(effects
				(font
					(size 1.27 1.27)
				)
				(justify right)
			)
		)
		(property "Value" "R_0R_0402"
			(at 255.27 226.06 0)
			(effects
				(font
					(size 1.27 1.27)
					(thickness 0.15)
				)
				(justify left bottom)
				(hide yes)
			)
		)
		(property "Footprint" "antmicro-footprints:R_0402_1005Metric"
			(at 257.81 226.06 0)
			(effects
				(font
					(size 1.27 1.27)
					(thickness 0.15)
				)
				(justify left bottom)
				(hide yes)
			)
		)
		(property "Datasheet" "https://industrial.panasonic.com/cdbs/www-data/pdf/RDA0000/AOA0000C301.pdf"
			(at 260.35 226.06 0)
			(effects
				(font
					(size 1.27 1.27)
					(thickness 0.15)
				)
				(justify left bottom)
				(hide yes)
			)
		)
		(property "Description" ""
			(at 242.57 246.38 0)
			(effects
				(font
					(size 1.27 1.27)
				)
			)
		)
		(property "Manufacturer" "Panasonic"
			(at 265.43 226.06 0)
			(effects
				(font
					(size 1.27 1.27)
					(thickness 0.15)
				)
				(justify left bottom)
				(hide yes)
			)
		)
		(property "MPN" "ERJ2GE0R00X"
			(at 262.89 226.06 0)
			(effects
				(font
					(size 1.27 1.27)
					(thickness 0.15)
				)
				(justify left bottom)
				(hide yes)
			)
		)
		(property "Val" "0R"
			(at 244.475 245.11 90)
			(effects
				(font
					(size 1.27 1.27)
					(thickness 0.15)
				)
				(justify right)
			)
		)
		(property "DNP" "DNP"
			(at 242.57 241.935 0)
			(effects
				(font
					(size 1.27 1.27)
				)
				(justify right)
			)
		)
		(property "License" "Apache-2.0"
			(at 267.97 226.06 0)
			(effects
				(font
					(size 1.27 1.27)
					(thickness 0.15)
				)
				(justify left bottom)
				(hide yes)
			)
		)
		(property "Author" "Antmicro"
			(at 270.51 226.06 0)
			(effects
				(font
					(size 1.27 1.27)
					(thickness 0.15)
				)
				(justify left bottom)
				(hide yes)
			)
		)
		(property "Tolerance" "~"
			(at 252.73 226.06 0)
			(effects
				(font
					(size 1.27 1.27)
				)
				(justify left bottom)
				(hide yes)
			)
		)
		(property "Current" "1A"
			(at 244.475 247.6499 90)
			(effects
				(font
					(size 1.27 1.27)
					(thickness 0.15)
				)
				(justify right)
				(hide yes)
			)
		)
		(pin "1"
		)
		(pin "2"
		)
		(instances
			(project "k410t-devboard"
				(path ""
					(reference "R316")
					(unit 1)
				)
			)
		)
	)
	(symbol
		(lib_id "antmicropower:+3V3_AON")
		(at 154.94 16.51 0)
		(unit 1)
		(exclude_from_sim no)
		(in_bom yes)
		(on_board yes)
		(dnp no)
		(property "Reference" "#PWR0474"
			(at 154.94 20.32 0)
			(effects
				(font
					(size 1.27 1.27)
				)
				(hide yes)
			)
		)
		(property "Value" "+3V3_AON"
			(at 154.94 12.954 0)
			(effects
				(font
					(size 1.27 1.27)
				)
			)
		)
		(property "Footprint" ""
			(at 154.94 16.51 0)
			(effects
				(font
					(size 1.27 1.27)
				)
				(hide yes)
			)
		)
		(property "Datasheet" ""
			(at 154.94 16.51 0)
			(effects
				(font
					(size 1.27 1.27)
				)
				(hide yes)
			)
		)
		(property "Description" ""
			(at 154.94 16.51 0)
			(effects
				(font
					(size 1.27 1.27)
				)
			)
		)
		(pin "1"
		)
		(instances
			(project "k410t-devboard"
				(path ""
					(reference "#PWR0474")
					(unit 1)
				)
			)
		)
	)
	(symbol
		(lib_id "antmicropower:+1V35")
		(at 151.13 246.38 0)
		(unit 1)
		(exclude_from_sim no)
		(in_bom yes)
		(on_board yes)
		(dnp no)
		(property "Reference" "#PWR0361"
			(at 151.13 250.19 0)
			(effects
				(font
					(size 1.27 1.27)
				)
				(hide yes)
			)
		)
		(property "Value" "+1V35"
			(at 151.13 242.824 0)
			(effects
				(font
					(size 1.27 1.27)
				)
			)
		)
		(property "Footprint" ""
			(at 151.13 246.38 0)
			(effects
				(font
					(size 1.27 1.27)
				)
				(hide yes)
			)
		)
		(property "Datasheet" ""
			(at 151.13 246.38 0)
			(effects
				(font
					(size 1.27 1.27)
				)
				(hide yes)
			)
		)
		(property "Description" ""
			(at 151.13 246.38 0)
			(effects
				(font
					(size 1.27 1.27)
				)
			)
		)
		(pin "1"
		)
		(instances
			(project "k410t-devboard"
				(path ""
					(reference "#PWR0361")
					(unit 1)
				)
			)
		)
	)
	(symbol
		(lib_id "antmicroCapacitors0603:C_22u_0603")
		(at 110.49 190.5 90)
		(unit 1)
		(exclude_from_sim no)
		(in_bom yes)
		(on_board yes)
		(dnp no)
		(property "Reference" "C324"
			(at 111.125 186.055 90)
			(effects
				(font
					(size 1.27 1.27)
				)
				(justify right)
			)
		)
		(property "Value" "C_22u_0603"
			(at 120.65 170.18 0)
			(effects
				(font
					(size 1.27 1.27)
					(thickness 0.15)
				)
				(justify left bottom)
				(hide yes)
			)
		)
		(property "Footprint" "antmicro-footprints:C_0603_1608Metric"
			(at 123.19 170.18 0)
			(effects
				(font
					(size 1.27 1.27)
					(thickness 0.15)
				)
				(justify left bottom)
				(hide yes)
			)
		)
		(property "Datasheet" "https://www.murata.com/products/productdetail?partno=GRM188R60J226MEA0%23"
			(at 125.73 170.18 0)
			(effects
				(font
					(size 1.27 1.27)
					(thickness 0.15)
				)
				(justify left bottom)
				(hide yes)
			)
		)
		(property "Description" ""
			(at 110.49 190.5 0)
			(effects
				(font
					(size 1.27 1.27)
				)
			)
		)
		(property "Manufacturer" "Murata"
			(at 130.81 170.18 0)
			(effects
				(font
					(size 1.27 1.27)
					(thickness 0.15)
				)
				(justify left bottom)
				(hide yes)
			)
		)
		(property "MPN" "GRM188R60J226MEA0D"
			(at 128.27 170.18 0)
			(effects
				(font
					(size 1.27 1.27)
					(thickness 0.15)
				)
				(justify left bottom)
				(hide yes)
			)
		)
		(property "Val" "22u"
			(at 111.125 189.865 90)
			(effects
				(font
					(size 1.27 1.27)
					(thickness 0.15)
				)
				(justify right)
			)
		)
		(property "License" "Apache-2.0"
			(at 133.35 170.18 0)
			(effects
				(font
					(size 1.27 1.27)
					(thickness 0.15)
				)
				(justify left bottom)
				(hide yes)
			)
		)
		(property "Author" "Antmicro"
			(at 135.89 170.18 0)
			(effects
				(font
					(size 1.27 1.27)
					(thickness 0.15)
				)
				(justify left bottom)
				(hide yes)
			)
		)
		(property "Voltage" ""
			(at 138.43 170.18 0)
			(effects
				(font
					(size 1.27 1.27)
				)
				(justify left bottom)
				(hide yes)
			)
		)
		(property "Dielectric" ""
			(at 140.97 170.18 0)
			(effects
				(font
					(size 1.27 1.27)
				)
				(justify left bottom)
				(hide yes)
			)
		)
		(pin "1"
		)
		(pin "2"
		)
		(instances
			(project "k410t-devboard"
				(path ""
					(reference "C324")
					(unit 1)
				)
			)
		)
	)
	(symbol
		(lib_id "antmicropower:+1V85_ADC")
		(at 396.24 149.86 0)
		(unit 1)
		(exclude_from_sim no)
		(in_bom yes)
		(on_board yes)
		(dnp no)
		(fields_autoplaced yes)
		(property "Reference" "#PWR0406"
			(at 396.24 153.67 0)
			(effects
				(font
					(size 1.27 1.27)
				)
				(hide yes)
			)
		)
		(property "Value" "+1V85_ADC"
			(at 396.24 146.304 0)
			(effects
				(font
					(size 1.27 1.27)
				)
			)
		)
		(property "Footprint" ""
			(at 396.24 149.86 0)
			(effects
				(font
					(size 1.27 1.27)
				)
				(hide yes)
			)
		)
		(property "Datasheet" ""
			(at 396.24 149.86 0)
			(effects
				(font
					(size 1.27 1.27)
				)
				(hide yes)
			)
		)
		(property "Description" ""
			(at 396.24 149.86 0)
			(effects
				(font
					(size 1.27 1.27)
				)
			)
		)
		(pin "1"
		)
		(instances
			(project "k410t-devboard"
				(path ""
					(reference "#PWR0406")
					(unit 1)
				)
			)
		)
	)
	(symbol
		(lib_id "antmicropower:+3.3V")
		(at 393.7 207.01 0)
		(unit 1)
		(exclude_from_sim no)
		(in_bom yes)
		(on_board yes)
		(dnp no)
		(fields_autoplaced yes)
		(property "Reference" "#PWR0502"
			(at 393.7 210.82 0)
			(effects
				(font
					(size 1.27 1.27)
				)
				(hide yes)
			)
		)
		(property "Value" "+3V3"
			(at 393.7 203.454 0)
			(effects
				(font
					(size 1.27 1.27)
				)
			)
		)
		(property "Footprint" ""
			(at 393.7 207.01 0)
			(effects
				(font
					(size 1.27 1.27)
				)
				(hide yes)
			)
		)
		(property "Datasheet" ""
			(at 393.7 207.01 0)
			(effects
				(font
					(size 1.27 1.27)
				)
				(hide yes)
			)
		)
		(property "Description" ""
			(at 393.7 207.01 0)
			(effects
				(font
					(size 1.27 1.27)
				)
			)
		)
		(pin "1"
		)
		(instances
			(project "k410t-devboard"
				(path ""
					(reference "#PWR0502")
					(unit 1)
				)
			)
		)
	)
	(symbol
		(lib_id "antmicropower:GND")
		(at 55.88 53.34 0)
		(unit 1)
		(exclude_from_sim no)
		(in_bom yes)
		(on_board yes)
		(dnp no)
		(property "Reference" "#PWR0365"
			(at 55.88 59.69 0)
			(effects
				(font
					(size 1.27 1.27)
				)
				(hide yes)
			)
		)
		(property "Value" "GND"
			(at 55.88 57.15 0)
			(effects
				(font
					(size 1.27 1.27)
				)
			)
		)
		(property "Footprint" ""
			(at 64.77 60.96 0)
			(effects
				(font
					(size 1.27 1.27)
					(thickness 0.15)
				)
				(justify left bottom)
				(hide yes)
			)
		)
		(property "Datasheet" ""
			(at 64.77 66.04 0)
			(effects
				(font
					(size 1.27 1.27)
					(thickness 0.15)
				)
				(justify left bottom)
				(hide yes)
			)
		)
		(property "Description" ""
			(at 55.88 53.34 0)
			(effects
				(font
					(size 1.27 1.27)
				)
			)
		)
		(property "Author" "Antmicro"
			(at 64.77 60.96 0)
			(effects
				(font
					(size 1.27 1.27)
					(thickness 0.15)
				)
				(justify left bottom)
				(hide yes)
			)
		)
		(property "License" "Apache-2.0"
			(at 64.77 63.5 0)
			(effects
				(font
					(size 1.27 1.27)
					(thickness 0.15)
				)
				(justify left bottom)
				(hide yes)
			)
		)
		(pin "1"
		)
		(instances
			(project "k410t-devboard"
				(path ""
					(reference "#PWR0365")
					(unit 1)
				)
			)
		)
	)
	(symbol
		(lib_id "antmicroResistors0402:R_0R_0402")
		(at 242.57 236.22 90)
		(unit 1)
		(exclude_from_sim no)
		(in_bom yes)
		(on_board yes)
		(dnp no)
		(fields_autoplaced yes)
		(property "Reference" "R315"
			(at 244.475 232.4099 90)
			(effects
				(font
					(size 1.27 1.27)
				)
				(justify right)
			)
		)
		(property "Value" "R_0R_0402"
			(at 255.27 215.9 0)
			(effects
				(font
					(size 1.27 1.27)
					(thickness 0.15)
				)
				(justify left bottom)
				(hide yes)
			)
		)
		(property "Footprint" "antmicro-footprints:R_0402_1005Metric"
			(at 257.81 215.9 0)
			(effects
				(font
					(size 1.27 1.27)
					(thickness 0.15)
				)
				(justify left bottom)
				(hide yes)
			)
		)
		(property "Datasheet" "https://industrial.panasonic.com/cdbs/www-data/pdf/RDA0000/AOA0000C301.pdf"
			(at 260.35 215.9 0)
			(effects
				(font
					(size 1.27 1.27)
					(thickness 0.15)
				)
				(justify left bottom)
				(hide yes)
			)
		)
		(property "Description" ""
			(at 242.57 236.22 0)
			(effects
				(font
					(size 1.27 1.27)
				)
			)
		)
		(property "Manufacturer" "Panasonic"
			(at 265.43 215.9 0)
			(effects
				(font
					(size 1.27 1.27)
					(thickness 0.15)
				)
				(justify left bottom)
				(hide yes)
			)
		)
		(property "MPN" "ERJ2GE0R00X"
			(at 262.89 215.9 0)
			(effects
				(font
					(size 1.27 1.27)
					(thickness 0.15)
				)
				(justify left bottom)
				(hide yes)
			)
		)
		(property "Val" "0R"
			(at 244.475 234.9499 90)
			(effects
				(font
					(size 1.27 1.27)
					(thickness 0.15)
				)
				(justify right)
			)
		)
		(property "License" "Apache-2.0"
			(at 267.97 215.9 0)
			(effects
				(font
					(size 1.27 1.27)
					(thickness 0.15)
				)
				(justify left bottom)
				(hide yes)
			)
		)
		(property "Author" "Antmicro"
			(at 270.51 215.9 0)
			(effects
				(font
					(size 1.27 1.27)
					(thickness 0.15)
				)
				(justify left bottom)
				(hide yes)
			)
		)
		(property "Tolerance" "~"
			(at 252.73 215.9 0)
			(effects
				(font
					(size 1.27 1.27)
				)
				(justify left bottom)
				(hide yes)
			)
		)
		(property "Current" "1A"
			(at 244.475 236.2199 90)
			(effects
				(font
					(size 1.27 1.27)
					(thickness 0.15)
				)
				(justify right)
				(hide yes)
			)
		)
		(pin "1"
		)
		(pin "2"
		)
		(instances
			(project "k410t-devboard"
				(path ""
					(reference "R315")
					(unit 1)
				)
			)
		)
	)
	(symbol
		(lib_id "antmicropower:GND")
		(at 119.38 144.78 0)
		(unit 1)
		(exclude_from_sim no)
		(in_bom yes)
		(on_board yes)
		(dnp no)
		(fields_autoplaced yes)
		(property "Reference" "#PWR0377"
			(at 119.38 151.13 0)
			(effects
				(font
					(size 1.27 1.27)
				)
				(hide yes)
			)
		)
		(property "Value" "GND"
			(at 119.38 148.59 0)
			(effects
				(font
					(size 1.27 1.27)
				)
			)
		)
		(property "Footprint" ""
			(at 128.27 152.4 0)
			(effects
				(font
					(size 1.27 1.27)
					(thickness 0.15)
				)
				(justify left bottom)
				(hide yes)
			)
		)
		(property "Datasheet" ""
			(at 128.27 157.48 0)
			(effects
				(font
					(size 1.27 1.27)
					(thickness 0.15)
				)
				(justify left bottom)
				(hide yes)
			)
		)
		(property "Description" ""
			(at 119.38 144.78 0)
			(effects
				(font
					(size 1.27 1.27)
				)
			)
		)
		(property "Author" "Antmicro"
			(at 128.27 152.4 0)
			(effects
				(font
					(size 1.27 1.27)
					(thickness 0.15)
				)
				(justify left bottom)
				(hide yes)
			)
		)
		(property "License" "Apache-2.0"
			(at 128.27 154.94 0)
			(effects
				(font
					(size 1.27 1.27)
					(thickness 0.15)
				)
				(justify left bottom)
				(hide yes)
			)
		)
		(pin "1"
		)
		(instances
			(project "k410t-devboard"
				(path ""
					(reference "#PWR0377")
					(unit 1)
				)
			)
		)
	)
	(symbol
		(lib_id "antmicroCapacitors0402:C_100n_0402")
		(at 290.83 171.45 90)
		(unit 1)
		(exclude_from_sim no)
		(in_bom yes)
		(on_board yes)
		(dnp no)
		(property "Reference" "C343"
			(at 291.465 167.005 90)
			(effects
				(font
					(size 1.27 1.27)
				)
				(justify right)
			)
		)
		(property "Value" "C_100n_0402"
			(at 300.99 151.13 0)
			(effects
				(font
					(size 1.27 1.27)
					(thickness 0.15)
				)
				(justify left bottom)
				(hide yes)
			)
		)
		(property "Footprint" "antmicro-footprints:C_0402_1005Metric"
			(at 303.53 151.13 0)
			(effects
				(font
					(size 1.27 1.27)
					(thickness 0.15)
				)
				(justify left bottom)
				(hide yes)
			)
		)
		(property "Datasheet" "https://www.murata.com/products/productdetail?partno=GRM155R61H104KE14%23"
			(at 306.07 151.13 0)
			(effects
				(font
					(size 1.27 1.27)
					(thickness 0.15)
				)
				(justify left bottom)
				(hide yes)
			)
		)
		(property "Description" ""
			(at 290.83 171.45 0)
			(effects
				(font
					(size 1.27 1.27)
				)
			)
		)
		(property "Manufacturer" "Murata"
			(at 311.15 151.13 0)
			(effects
				(font
					(size 1.27 1.27)
					(thickness 0.15)
				)
				(justify left bottom)
				(hide yes)
			)
		)
		(property "MPN" "GRM155R61H104KE14D"
			(at 308.61 151.13 0)
			(effects
				(font
					(size 1.27 1.27)
					(thickness 0.15)
				)
				(justify left bottom)
				(hide yes)
			)
		)
		(property "Val" "100n"
			(at 291.465 170.815 90)
			(effects
				(font
					(size 1.27 1.27)
					(thickness 0.15)
				)
				(justify right)
			)
		)
		(property "License" "Apache-2.0"
			(at 313.69 151.13 0)
			(effects
				(font
					(size 1.27 1.27)
					(thickness 0.15)
				)
				(justify left bottom)
				(hide yes)
			)
		)
		(property "Author" "Antmicro"
			(at 316.23 151.13 0)
			(effects
				(font
					(size 1.27 1.27)
					(thickness 0.15)
				)
				(justify left bottom)
				(hide yes)
			)
		)
		(property "Voltage" "50V"
			(at 318.77 151.13 0)
			(effects
				(font
					(size 1.27 1.27)
				)
				(justify left bottom)
				(hide yes)
			)
		)
		(property "Dielectric" "X5R"
			(at 321.31 151.13 0)
			(effects
				(font
					(size 1.27 1.27)
				)
				(justify left bottom)
				(hide yes)
			)
		)
		(pin "1"
		)
		(pin "2"
		)
		(instances
			(project "k410t-devboard"
				(path ""
					(reference "C343")
					(unit 1)
				)
			)
		)
	)
	(symbol
		(lib_id "antmicroResistors0402:R_80k6_0402")
		(at 388.62 63.5 90)
		(unit 1)
		(exclude_from_sim no)
		(in_bom yes)
		(on_board yes)
		(dnp no)
		(fields_autoplaced yes)
		(property "Reference" "R331"
			(at 390.525 59.6899 90)
			(effects
				(font
					(size 1.27 1.27)
				)
				(justify right)
			)
		)
		(property "Value" "R_80k6_0402"
			(at 401.32 43.18 0)
			(effects
				(font
					(size 1.27 1.27)
					(thickness 0.15)
				)
				(justify left bottom)
				(hide yes)
			)
		)
		(property "Footprint" "antmicro-footprints:R_0402_1005Metric"
			(at 403.86 43.18 0)
			(effects
				(font
					(size 1.27 1.27)
					(thickness 0.15)
				)
				(justify left bottom)
				(hide yes)
			)
		)
		(property "Datasheet" "https://www.bourns.com/docs/product-datasheets/cr.pdf"
			(at 406.4 43.18 0)
			(effects
				(font
					(size 1.27 1.27)
					(thickness 0.15)
				)
				(justify left bottom)
				(hide yes)
			)
		)
		(property "Description" ""
			(at 388.62 63.5 0)
			(effects
				(font
					(size 1.27 1.27)
				)
			)
		)
		(property "Manufacturer" "Bourns"
			(at 411.48 43.18 0)
			(effects
				(font
					(size 1.27 1.27)
					(thickness 0.15)
				)
				(justify left bottom)
				(hide yes)
			)
		)
		(property "MPN" "CR0402-FX-8062GLF"
			(at 408.94 43.18 0)
			(effects
				(font
					(size 1.27 1.27)
					(thickness 0.15)
				)
				(justify left bottom)
				(hide yes)
			)
		)
		(property "Val" "80k6"
			(at 390.525 62.2299 90)
			(effects
				(font
					(size 1.27 1.27)
					(thickness 0.15)
				)
				(justify right)
			)
		)
		(property "License" "Apache-2.0"
			(at 414.02 43.18 0)
			(effects
				(font
					(size 1.27 1.27)
					(thickness 0.15)
				)
				(justify left bottom)
				(hide yes)
			)
		)
		(property "Author" "Antmicro"
			(at 416.56 43.18 0)
			(effects
				(font
					(size 1.27 1.27)
					(thickness 0.15)
				)
				(justify left bottom)
				(hide yes)
			)
		)
		(property "Tolerance" "1%"
			(at 398.78 43.18 0)
			(effects
				(font
					(size 1.27 1.27)
				)
				(justify left bottom)
				(hide yes)
			)
		)
		(pin "1"
		)
		(pin "2"
		)
		(instances
			(project "k410t-devboard"
				(path ""
					(reference "R331")
					(unit 1)
				)
			)
		)
	)
	(symbol
		(lib_id "antmicropower:GND")
		(at 110.49 259.08 0)
		(unit 1)
		(exclude_from_sim no)
		(in_bom yes)
		(on_board yes)
		(dnp no)
		(property "Reference" "#PWR0374"
			(at 110.49 265.43 0)
			(effects
				(font
					(size 1.27 1.27)
				)
				(hide yes)
			)
		)
		(property "Value" "GND"
			(at 110.49 262.89 0)
			(effects
				(font
					(size 1.27 1.27)
				)
			)
		)
		(property "Footprint" ""
			(at 119.38 266.7 0)
			(effects
				(font
					(size 1.27 1.27)
					(thickness 0.15)
				)
				(justify left bottom)
				(hide yes)
			)
		)
		(property "Datasheet" ""
			(at 119.38 271.78 0)
			(effects
				(font
					(size 1.27 1.27)
					(thickness 0.15)
				)
				(justify left bottom)
				(hide yes)
			)
		)
		(property "Description" ""
			(at 110.49 259.08 0)
			(effects
				(font
					(size 1.27 1.27)
				)
			)
		)
		(property "Author" "Antmicro"
			(at 119.38 266.7 0)
			(effects
				(font
					(size 1.27 1.27)
					(thickness 0.15)
				)
				(justify left bottom)
				(hide yes)
			)
		)
		(property "License" "Apache-2.0"
			(at 119.38 269.24 0)
			(effects
				(font
					(size 1.27 1.27)
					(thickness 0.15)
				)
				(justify left bottom)
				(hide yes)
			)
		)
		(pin "1"
		)
		(instances
			(project "k410t-devboard"
				(path ""
					(reference "#PWR0374")
					(unit 1)
				)
			)
		)
	)
	(symbol
		(lib_id "antmicropower:GND")
		(at 124.46 25.4 0)
		(unit 1)
		(exclude_from_sim no)
		(in_bom yes)
		(on_board yes)
		(dnp no)
		(property "Reference" "#PWR0388"
			(at 124.46 31.75 0)
			(effects
				(font
					(size 1.27 1.27)
				)
				(hide yes)
			)
		)
		(property "Value" "GND"
			(at 124.46 29.21 0)
			(effects
				(font
					(size 1.27 1.27)
				)
			)
		)
		(property "Footprint" ""
			(at 133.35 33.02 0)
			(effects
				(font
					(size 1.27 1.27)
					(thickness 0.15)
				)
				(justify left bottom)
				(hide yes)
			)
		)
		(property "Datasheet" ""
			(at 133.35 38.1 0)
			(effects
				(font
					(size 1.27 1.27)
					(thickness 0.15)
				)
				(justify left bottom)
				(hide yes)
			)
		)
		(property "Description" ""
			(at 124.46 25.4 0)
			(effects
				(font
					(size 1.27 1.27)
				)
			)
		)
		(property "Author" "Antmicro"
			(at 133.35 33.02 0)
			(effects
				(font
					(size 1.27 1.27)
					(thickness 0.15)
				)
				(justify left bottom)
				(hide yes)
			)
		)
		(property "License" "Apache-2.0"
			(at 133.35 35.56 0)
			(effects
				(font
					(size 1.27 1.27)
					(thickness 0.15)
				)
				(justify left bottom)
				(hide yes)
			)
		)
		(pin "1"
		)
		(instances
			(project "k410t-devboard"
				(path ""
					(reference "#PWR0388")
					(unit 1)
				)
			)
		)
	)
	(symbol
		(lib_id "antmicropower:+1V0_MGTAVCC")
		(at 140.97 88.9 0)
		(unit 1)
		(exclude_from_sim no)
		(in_bom yes)
		(on_board yes)
		(dnp no)
		(fields_autoplaced yes)
		(property "Reference" "#PWR0447"
			(at 140.97 92.71 0)
			(effects
				(font
					(size 1.27 1.27)
				)
				(hide yes)
			)
		)
		(property "Value" "+1V0_MGTAVCC"
			(at 140.97 85.09 0)
			(effects
				(font
					(size 1.27 1.27)
				)
			)
		)
		(property "Footprint" ""
			(at 140.97 88.9 0)
			(effects
				(font
					(size 1.27 1.27)
				)
				(hide yes)
			)
		)
		(property "Datasheet" ""
			(at 140.97 88.9 0)
			(effects
				(font
					(size 1.27 1.27)
				)
				(hide yes)
			)
		)
		(property "Description" ""
			(at 140.97 88.9 0)
			(effects
				(font
					(size 1.27 1.27)
				)
			)
		)
		(pin "1"
		)
		(instances
			(project "k410t-devboard"
				(path ""
					(reference "#PWR0447")
					(unit 1)
				)
			)
		)
	)
	(symbol
		(lib_id "antmicroResistors0402:R_0R_0402")
		(at 64.77 240.03 90)
		(unit 1)
		(exclude_from_sim no)
		(in_bom yes)
		(on_board yes)
		(dnp no)
		(property "Reference" "R280"
			(at 63.5 236.22 90)
			(effects
				(font
					(size 1.27 1.27)
				)
				(justify left)
			)
		)
		(property "Value" "R_0R_0402"
			(at 68.58 240.03 0)
			(effects
				(font
					(size 1.27 1.27)
				)
				(hide yes)
			)
		)
		(property "Footprint" "antmicro-footprints:R_0402_1005Metric"
			(at 59.69 234.95 0)
			(effects
				(font
					(size 1.27 1.27)
				)
				(justify left)
				(hide yes)
			)
		)
		(property "Datasheet" "https://industrial.panasonic.com/cdbs/www-data/pdf/RDA0000/AOA0000C301.pdf"
			(at 64.77 240.03 0)
			(effects
				(font
					(size 1.27 1.27)
				)
				(hide yes)
			)
		)
		(property "Description" ""
			(at 64.77 240.03 0)
			(effects
				(font
					(size 1.27 1.27)
				)
			)
		)
		(property "Manufacturer" "Panasonic"
			(at 54.61 234.95 0)
			(effects
				(font
					(size 1.27 1.27)
				)
				(justify left)
				(hide yes)
			)
		)
		(property "MPN" "ERJ2GE0R00X"
			(at 57.15 234.95 0)
			(effects
				(font
					(size 1.27 1.27)
				)
				(justify left)
				(hide yes)
			)
		)
		(property "Val" "0R"
			(at 63.5 238.76 90)
			(effects
				(font
					(size 1.27 1.27)
				)
				(justify left)
			)
		)
		(property "License" "Apache-2.0"
			(at 90.17 219.71 0)
			(effects
				(font
					(size 1.27 1.27)
					(thickness 0.15)
				)
				(justify left bottom)
				(hide yes)
			)
		)
		(property "Author" "Antmicro"
			(at 92.71 219.71 0)
			(effects
				(font
					(size 1.27 1.27)
					(thickness 0.15)
				)
				(justify left bottom)
				(hide yes)
			)
		)
		(property "Tolerance" "~"
			(at 74.93 219.71 0)
			(effects
				(font
					(size 1.27 1.27)
				)
				(justify left bottom)
				(hide yes)
			)
		)
		(property "Current" "1A"
			(at 62.23 240.0299 90)
			(effects
				(font
					(size 1.27 1.27)
					(thickness 0.15)
				)
				(justify left)
				(hide yes)
			)
		)
		(pin "1"
		)
		(pin "2"
		)
		(instances
			(project "k410t-devboard"
				(path ""
					(reference "R280")
					(unit 1)
				)
			)
		)
	)
	(symbol
		(lib_id "antmicropower:VDC")
		(at 49.53 92.71 0)
		(unit 1)
		(exclude_from_sim no)
		(in_bom yes)
		(on_board yes)
		(dnp no)
		(fields_autoplaced yes)
		(property "Reference" "#PWR0331"
			(at 49.53 95.25 0)
			(effects
				(font
					(size 1.27 1.27)
				)
				(hide yes)
			)
		)
		(property "Value" "VDC"
			(at 49.53 87.63 0)
			(effects
				(font
					(size 1.27 1.27)
				)
			)
		)
		(property "Footprint" ""
			(at 49.53 92.71 0)
			(effects
				(font
					(size 1.27 1.27)
				)
				(hide yes)
			)
		)
		(property "Datasheet" ""
			(at 49.53 92.71 0)
			(effects
				(font
					(size 1.27 1.27)
				)
				(hide yes)
			)
		)
		(property "Description" ""
			(at 49.53 92.71 0)
			(effects
				(font
					(size 1.27 1.27)
				)
			)
		)
		(pin "1"
		)
		(instances
			(project "k410t-devboard"
				(path ""
					(reference "#PWR0331")
					(unit 1)
				)
			)
		)
	)
	(symbol
		(lib_id "antmicroFixedInductors:L_1u5_17A_Bourns-SRP6050CA")
		(at 345.44 45.72 0)
		(unit 1)
		(exclude_from_sim no)
		(in_bom yes)
		(on_board yes)
		(dnp no)
		(property "Reference" "L1"
			(at 347.98 41.275 0)
			(effects
				(font
					(size 1.27 1.27)
				)
			)
		)
		(property "Value" "L_1u5_17A_Bourns-SRP6050CA"
			(at 359.41 48.26 0)
			(effects
				(font
					(size 1.27 1.27)
					(thickness 0.15)
				)
				(justify left bottom)
				(hide yes)
			)
		)
		(property "Footprint" "antmicro-footprints:L_Bourns-SRP6050CA"
			(at 359.41 53.34 0)
			(effects
				(font
					(size 1.27 1.27)
					(thickness 0.15)
				)
				(justify left bottom)
				(hide yes)
			)
		)
		(property "Datasheet" "https://www.bourns.com/docs/Product-Datasheets/SRP6050CA.pdf"
			(at 359.41 55.88 0)
			(effects
				(font
					(size 1.27 1.27)
					(thickness 0.15)
				)
				(justify left bottom)
				(hide yes)
			)
		)
		(property "Description" ""
			(at 345.44 45.72 0)
			(effects
				(font
					(size 1.27 1.27)
				)
			)
		)
		(property "Manufacturer" "Bourns"
			(at 359.41 58.42 0)
			(effects
				(font
					(size 1.27 1.27)
					(thickness 0.15)
				)
				(justify left bottom)
				(hide yes)
			)
		)
		(property "MPN" "SRP6050CA-1R5M"
			(at 359.41 60.96 0)
			(effects
				(font
					(size 1.27 1.27)
					(thickness 0.15)
				)
				(justify left bottom)
				(hide yes)
			)
		)
		(property "Size" "6.6x6.6"
			(at 359.41 68.58 0)
			(effects
				(font
					(size 1.27 1.27)
					(thickness 0.15)
				)
				(justify left bottom)
				(hide yes)
			)
		)
		(property "Val" "1u5/17A"
			(at 347.98 43.815 0)
			(effects
				(font
					(size 1.27 1.27)
					(thickness 0.15)
				)
			)
		)
		(property "ISat" "19.5 A"
			(at 359.41 62.23 0)
			(effects
				(font
					(size 1.27 1.27)
				)
				(justify left)
				(hide yes)
			)
		)
		(property "IMax" "17 A"
			(at 359.41 66.04 0)
			(effects
				(font
					(size 1.27 1.27)
					(thickness 0.15)
				)
				(justify left bottom)
				(hide yes)
			)
		)
		(property "Author" "Antmicro"
			(at 359.41 71.12 0)
			(effects
				(font
					(size 1.27 1.27)
					(thickness 0.15)
				)
				(justify left bottom)
				(hide yes)
			)
		)
		(property "License" "Apache-2.0"
			(at 359.41 73.66 0)
			(effects
				(font
					(size 1.27 1.27)
					(thickness 0.15)
				)
				(justify left bottom)
				(hide yes)
			)
		)
		(pin "1"
		)
		(pin "2"
		)
		(instances
			(project "k410t-devboard"
				(path ""
					(reference "L1")
					(unit 1)
				)
			)
		)
	)
	(symbol
		(lib_id "antmicropower:GND")
		(at 189.23 218.44 0)
		(unit 1)
		(exclude_from_sim no)
		(in_bom yes)
		(on_board yes)
		(dnp no)
		(fields_autoplaced yes)
		(property "Reference" "#PWR0397"
			(at 189.23 224.79 0)
			(effects
				(font
					(size 1.27 1.27)
				)
				(hide yes)
			)
		)
		(property "Value" "GND"
			(at 189.23 222.25 0)
			(effects
				(font
					(size 1.27 1.27)
				)
			)
		)
		(property "Footprint" ""
			(at 198.12 226.06 0)
			(effects
				(font
					(size 1.27 1.27)
					(thickness 0.15)
				)
				(justify left bottom)
				(hide yes)
			)
		)
		(property "Datasheet" ""
			(at 198.12 231.14 0)
			(effects
				(font
					(size 1.27 1.27)
					(thickness 0.15)
				)
				(justify left bottom)
				(hide yes)
			)
		)
		(property "Description" ""
			(at 189.23 218.44 0)
			(effects
				(font
					(size 1.27 1.27)
				)
			)
		)
		(property "Author" "Antmicro"
			(at 198.12 226.06 0)
			(effects
				(font
					(size 1.27 1.27)
					(thickness 0.15)
				)
				(justify left bottom)
				(hide yes)
			)
		)
		(property "License" "Apache-2.0"
			(at 198.12 228.6 0)
			(effects
				(font
					(size 1.27 1.27)
					(thickness 0.15)
				)
				(justify left bottom)
				(hide yes)
			)
		)
		(pin "1"
		)
		(instances
			(project "k410t-devboard"
				(path ""
					(reference "#PWR0397")
					(unit 1)
				)
			)
		)
	)
	(symbol
		(lib_id "antmicropower:GND")
		(at 142.24 72.39 0)
		(unit 1)
		(exclude_from_sim no)
		(in_bom yes)
		(on_board yes)
		(dnp no)
		(property "Reference" "#PWR0390"
			(at 142.24 78.74 0)
			(effects
				(font
					(size 1.27 1.27)
				)
				(hide yes)
			)
		)
		(property "Value" "GND"
			(at 142.24 76.2 0)
			(effects
				(font
					(size 1.27 1.27)
				)
			)
		)
		(property "Footprint" ""
			(at 151.13 80.01 0)
			(effects
				(font
					(size 1.27 1.27)
					(thickness 0.15)
				)
				(justify left bottom)
				(hide yes)
			)
		)
		(property "Datasheet" ""
			(at 151.13 85.09 0)
			(effects
				(font
					(size 1.27 1.27)
					(thickness 0.15)
				)
				(justify left bottom)
				(hide yes)
			)
		)
		(property "Description" ""
			(at 142.24 72.39 0)
			(effects
				(font
					(size 1.27 1.27)
				)
			)
		)
		(property "Author" "Antmicro"
			(at 151.13 80.01 0)
			(effects
				(font
					(size 1.27 1.27)
					(thickness 0.15)
				)
				(justify left bottom)
				(hide yes)
			)
		)
		(property "License" "Apache-2.0"
			(at 151.13 82.55 0)
			(effects
				(font
					(size 1.27 1.27)
					(thickness 0.15)
				)
				(justify left bottom)
				(hide yes)
			)
		)
		(pin "1"
		)
		(instances
			(project "k410t-devboard"
				(path ""
					(reference "#PWR0390")
					(unit 1)
				)
			)
		)
	)
	(symbol
		(lib_id "antmicroCapacitors0402:C_470n_0402")
		(at 281.94 60.96 90)
		(unit 1)
		(exclude_from_sim no)
		(in_bom yes)
		(on_board yes)
		(dnp no)
		(fields_autoplaced yes)
		(property "Reference" "C342"
			(at 285.115 57.1435 90)
			(effects
				(font
					(size 1.27 1.27)
				)
				(justify right)
			)
		)
		(property "Value" "C_470n_0402"
			(at 292.1 40.64 0)
			(effects
				(font
					(size 1.27 1.27)
					(thickness 0.15)
				)
				(justify left bottom)
				(hide yes)
			)
		)
		(property "Footprint" "antmicro-footprints:C_0402_1005Metric"
			(at 294.64 40.64 0)
			(effects
				(font
					(size 1.27 1.27)
					(thickness 0.15)
				)
				(justify left bottom)
				(hide yes)
			)
		)
		(property "Datasheet" "https://product.tdk.com/en/search/capacitor/ceramic/mlcc/info?part_no=C1005X5R1E474M050BB"
			(at 297.18 40.64 0)
			(effects
				(font
					(size 1.27 1.27)
					(thickness 0.15)
				)
				(justify left bottom)
				(hide yes)
			)
		)
		(property "Description" ""
			(at 281.94 60.96 0)
			(effects
				(font
					(size 1.27 1.27)
				)
			)
		)
		(property "Manufacturer" "TDK"
			(at 302.26 40.64 0)
			(effects
				(font
					(size 1.27 1.27)
					(thickness 0.15)
				)
				(justify left bottom)
				(hide yes)
			)
		)
		(property "MPN" "C1005X5R1E474M050BB"
			(at 299.72 40.64 0)
			(effects
				(font
					(size 1.27 1.27)
					(thickness 0.15)
				)
				(justify left bottom)
				(hide yes)
			)
		)
		(property "Val" "470n"
			(at 285.115 59.6835 90)
			(effects
				(font
					(size 1.27 1.27)
					(thickness 0.15)
				)
				(justify right)
			)
		)
		(property "License" "Apache-2.0"
			(at 304.8 40.64 0)
			(effects
				(font
					(size 1.27 1.27)
					(thickness 0.15)
				)
				(justify left bottom)
				(hide yes)
			)
		)
		(property "Author" "Antmicro"
			(at 307.34 40.64 0)
			(effects
				(font
					(size 1.27 1.27)
					(thickness 0.15)
				)
				(justify left bottom)
				(hide yes)
			)
		)
		(property "Voltage" ""
			(at 309.88 40.64 0)
			(effects
				(font
					(size 1.27 1.27)
				)
				(justify left bottom)
				(hide yes)
			)
		)
		(property "Dielectric" ""
			(at 312.42 40.64 0)
			(effects
				(font
					(size 1.27 1.27)
				)
				(justify left bottom)
				(hide yes)
			)
		)
		(pin "1"
		)
		(pin "2"
		)
		(instances
			(project "k410t-devboard"
				(path ""
					(reference "C342")
					(unit 1)
				)
			)
		)
	)
	(symbol
		(lib_id "antmicropower:GND")
		(at 119.38 194.31 0)
		(unit 1)
		(exclude_from_sim no)
		(in_bom yes)
		(on_board yes)
		(dnp no)
		(fields_autoplaced yes)
		(property "Reference" "#PWR0385"
			(at 119.38 200.66 0)
			(effects
				(font
					(size 1.27 1.27)
				)
				(hide yes)
			)
		)
		(property "Value" "GND"
			(at 119.38 198.12 0)
			(effects
				(font
					(size 1.27 1.27)
				)
			)
		)
		(property "Footprint" ""
			(at 128.27 201.93 0)
			(effects
				(font
					(size 1.27 1.27)
					(thickness 0.15)
				)
				(justify left bottom)
				(hide yes)
			)
		)
		(property "Datasheet" ""
			(at 128.27 207.01 0)
			(effects
				(font
					(size 1.27 1.27)
					(thickness 0.15)
				)
				(justify left bottom)
				(hide yes)
			)
		)
		(property "Description" ""
			(at 119.38 194.31 0)
			(effects
				(font
					(size 1.27 1.27)
				)
			)
		)
		(property "Author" "Antmicro"
			(at 128.27 201.93 0)
			(effects
				(font
					(size 1.27 1.27)
					(thickness 0.15)
				)
				(justify left bottom)
				(hide yes)
			)
		)
		(property "License" "Apache-2.0"
			(at 128.27 204.47 0)
			(effects
				(font
					(size 1.27 1.27)
					(thickness 0.15)
				)
				(justify left bottom)
				(hide yes)
			)
		)
		(pin "1"
		)
		(instances
			(project "k410t-devboard"
				(path ""
					(reference "#PWR0385")
					(unit 1)
				)
			)
		)
	)
	(symbol
		(lib_id "antmicroCapacitors0402:C_1u_0402")
		(at 151.13 266.7 90)
		(unit 1)
		(exclude_from_sim no)
		(in_bom no)
		(on_board yes)
		(dnp yes)
		(property "Reference" "C335"
			(at 151.765 262.255 90)
			(effects
				(font
					(size 1.27 1.27)
				)
				(justify right)
			)
		)
		(property "Value" "C_1u_0402"
			(at 161.29 246.38 0)
			(effects
				(font
					(size 1.27 1.27)
					(thickness 0.15)
				)
				(justify left bottom)
				(hide yes)
			)
		)
		(property "Footprint" "antmicro-footprints:C_0402_1005Metric"
			(at 163.83 246.38 0)
			(effects
				(font
					(size 1.27 1.27)
					(thickness 0.15)
				)
				(justify left bottom)
				(hide yes)
			)
		)
		(property "Datasheet" "https://product.tdk.com/en/search/capacitor/ceramic/mlcc/info?part_no=C1005X6S1A105K050BC"
			(at 166.37 246.38 0)
			(effects
				(font
					(size 1.27 1.27)
					(thickness 0.15)
				)
				(justify left bottom)
				(hide yes)
			)
		)
		(property "Description" ""
			(at 151.13 266.7 0)
			(effects
				(font
					(size 1.27 1.27)
				)
			)
		)
		(property "Manufacturer" "TDK"
			(at 171.45 246.38 0)
			(effects
				(font
					(size 1.27 1.27)
					(thickness 0.15)
				)
				(justify left bottom)
				(hide yes)
			)
		)
		(property "MPN" "C1005X6S1A105K050BC"
			(at 168.91 246.38 0)
			(effects
				(font
					(size 1.27 1.27)
					(thickness 0.15)
				)
				(justify left bottom)
				(hide yes)
			)
		)
		(property "Val" "1u"
			(at 151.765 266.065 90)
			(effects
				(font
					(size 1.27 1.27)
					(thickness 0.15)
				)
				(justify right)
			)
		)
		(property "DNP" "DNP"
			(at 153.035 264.16 90)
			(effects
				(font
					(size 1.27 1.27)
				)
				(justify right)
			)
		)
		(property "License" "Apache-2.0"
			(at 173.99 246.38 0)
			(effects
				(font
					(size 1.27 1.27)
					(thickness 0.15)
				)
				(justify left bottom)
				(hide yes)
			)
		)
		(property "Author" "Antmicro"
			(at 176.53 246.38 0)
			(effects
				(font
					(size 1.27 1.27)
					(thickness 0.15)
				)
				(justify left bottom)
				(hide yes)
			)
		)
		(property "Voltage" ""
			(at 179.07 246.38 0)
			(effects
				(font
					(size 1.27 1.27)
				)
				(justify left bottom)
				(hide yes)
			)
		)
		(property "Dielectric" ""
			(at 181.61 246.38 0)
			(effects
				(font
					(size 1.27 1.27)
				)
				(justify left bottom)
				(hide yes)
			)
		)
		(pin "1"
		)
		(pin "2"
		)
		(instances
			(project "k410t-devboard"
				(path ""
					(reference "C335")
					(unit 1)
				)
			)
		)
	)
	(symbol
		(lib_id "antmicropower:GND")
		(at 242.57 257.81 0)
		(unit 1)
		(exclude_from_sim no)
		(in_bom yes)
		(on_board yes)
		(dnp no)
		(fields_autoplaced yes)
		(property "Reference" "#PWR0409"
			(at 242.57 264.16 0)
			(effects
				(font
					(size 1.27 1.27)
				)
				(hide yes)
			)
		)
		(property "Value" "GND"
			(at 242.57 261.62 0)
			(effects
				(font
					(size 1.27 1.27)
				)
			)
		)
		(property "Footprint" ""
			(at 251.46 265.43 0)
			(effects
				(font
					(size 1.27 1.27)
					(thickness 0.15)
				)
				(justify left bottom)
				(hide yes)
			)
		)
		(property "Datasheet" ""
			(at 251.46 270.51 0)
			(effects
				(font
					(size 1.27 1.27)
					(thickness 0.15)
				)
				(justify left bottom)
				(hide yes)
			)
		)
		(property "Description" ""
			(at 242.57 257.81 0)
			(effects
				(font
					(size 1.27 1.27)
				)
			)
		)
		(property "Author" "Antmicro"
			(at 251.46 265.43 0)
			(effects
				(font
					(size 1.27 1.27)
					(thickness 0.15)
				)
				(justify left bottom)
				(hide yes)
			)
		)
		(property "License" "Apache-2.0"
			(at 251.46 267.97 0)
			(effects
				(font
					(size 1.27 1.27)
					(thickness 0.15)
				)
				(justify left bottom)
				(hide yes)
			)
		)
		(pin "1"
		)
		(instances
			(project "k410t-devboard"
				(path ""
					(reference "#PWR0409")
					(unit 1)
				)
			)
		)
	)
	(symbol
		(lib_id "antmicroCapacitorsmisc:C_22u_25V_0805")
		(at 59.69 100.33 90)
		(unit 1)
		(exclude_from_sim no)
		(in_bom yes)
		(on_board yes)
		(dnp no)
		(fields_autoplaced yes)
		(property "Reference" "C319"
			(at 62.23 95.2436 90)
			(effects
				(font
					(size 1.27 1.27)
				)
				(justify right)
			)
		)
		(property "Value" "C_22u_25V_0805"
			(at 63.5 100.33 0)
			(effects
				(font
					(size 1.27 1.27)
				)
				(hide yes)
			)
		)
		(property "Footprint" "antmicro-footprints:C_0805_2012Metric"
			(at 54.61 95.25 0)
			(effects
				(font
					(size 1.27 1.27)
				)
				(justify left)
				(hide yes)
			)
		)
		(property "Datasheet" "https://product.samsungsem.com/mlcc/CL21A226MAYNNN.do"
			(at 59.69 100.33 0)
			(effects
				(font
					(size 1.27 1.27)
				)
				(hide yes)
			)
		)
		(property "Description" ""
			(at 59.69 100.33 0)
			(effects
				(font
					(size 1.27 1.27)
				)
			)
		)
		(property "Manufacturer" "Samsung Electro-Mechanics"
			(at 49.53 95.25 0)
			(effects
				(font
					(size 1.27 1.27)
				)
				(justify left)
				(hide yes)
			)
		)
		(property "MPN" "CL21A226MAYNNNE"
			(at 52.07 95.25 0)
			(effects
				(font
					(size 1.27 1.27)
				)
				(justify left)
				(hide yes)
			)
		)
		(property "Val" "22u"
			(at 62.23 97.7836 90)
			(effects
				(font
					(size 1.27 1.27)
				)
				(justify right)
			)
		)
		(property "License" "Apache-2.0"
			(at 82.55 80.01 0)
			(effects
				(font
					(size 1.27 1.27)
					(thickness 0.15)
				)
				(justify left bottom)
				(hide yes)
			)
		)
		(property "Author" "Antmicro"
			(at 85.09 80.01 0)
			(effects
				(font
					(size 1.27 1.27)
					(thickness 0.15)
				)
				(justify left bottom)
				(hide yes)
			)
		)
		(property "Voltage" "25V"
			(at 62.23 100.3236 90)
			(effects
				(font
					(size 1.27 1.27)
				)
				(justify right)
			)
		)
		(property "Dielectric" "X5R"
			(at 90.17 80.01 0)
			(effects
				(font
					(size 1.27 1.27)
				)
				(justify left bottom)
				(hide yes)
			)
		)
		(pin "1"
		)
		(pin "2"
		)
		(instances
			(project "k410t-devboard"
				(path ""
					(reference "C319")
					(unit 1)
				)
			)
		)
	)
	(symbol
		(lib_id "antmicropower:+3.3V")
		(at 312.42 196.85 0)
		(unit 1)
		(exclude_from_sim no)
		(in_bom yes)
		(on_board yes)
		(dnp no)
		(fields_autoplaced yes)
		(property "Reference" "#PWR0389"
			(at 312.42 200.66 0)
			(effects
				(font
					(size 1.27 1.27)
				)
				(hide yes)
			)
		)
		(property "Value" "+3V3"
			(at 312.42 193.294 0)
			(effects
				(font
					(size 1.27 1.27)
				)
			)
		)
		(property "Footprint" ""
			(at 312.42 196.85 0)
			(effects
				(font
					(size 1.27 1.27)
				)
				(hide yes)
			)
		)
		(property "Datasheet" ""
			(at 312.42 196.85 0)
			(effects
				(font
					(size 1.27 1.27)
				)
				(hide yes)
			)
		)
		(property "Description" ""
			(at 312.42 196.85 0)
			(effects
				(font
					(size 1.27 1.27)
				)
			)
		)
		(pin "1"
		)
		(instances
			(project "k410t-devboard"
				(path ""
					(reference "#PWR0389")
					(unit 1)
				)
			)
		)
	)
	(symbol
		(lib_id "antmicropower:GND")
		(at 180.34 40.64 0)
		(unit 1)
		(exclude_from_sim no)
		(in_bom yes)
		(on_board yes)
		(dnp no)
		(property "Reference" "#PWR0393"
			(at 180.34 46.99 0)
			(effects
				(font
					(size 1.27 1.27)
				)
				(hide yes)
			)
		)
		(property "Value" "GND"
			(at 180.34 44.45 0)
			(effects
				(font
					(size 1.27 1.27)
				)
			)
		)
		(property "Footprint" ""
			(at 189.23 48.26 0)
			(effects
				(font
					(size 1.27 1.27)
					(thickness 0.15)
				)
				(justify left bottom)
				(hide yes)
			)
		)
		(property "Datasheet" ""
			(at 189.23 53.34 0)
			(effects
				(font
					(size 1.27 1.27)
					(thickness 0.15)
				)
				(justify left bottom)
				(hide yes)
			)
		)
		(property "Description" ""
			(at 180.34 40.64 0)
			(effects
				(font
					(size 1.27 1.27)
				)
			)
		)
		(property "Author" "Antmicro"
			(at 189.23 48.26 0)
			(effects
				(font
					(size 1.27 1.27)
					(thickness 0.15)
				)
				(justify left bottom)
				(hide yes)
			)
		)
		(property "License" "Apache-2.0"
			(at 189.23 50.8 0)
			(effects
				(font
					(size 1.27 1.27)
					(thickness 0.15)
				)
				(justify left bottom)
				(hide yes)
			)
		)
		(pin "1"
		)
		(instances
			(project "k410t-devboard"
				(path ""
					(reference "#PWR0393")
					(unit 1)
				)
			)
		)
	)
	(symbol
		(lib_id "antmicropower:+3V3_AON")
		(at 217.17 31.75 0)
		(unit 1)
		(exclude_from_sim no)
		(in_bom yes)
		(on_board yes)
		(dnp no)
		(fields_autoplaced yes)
		(property "Reference" "#PWR0475"
			(at 217.17 35.56 0)
			(effects
				(font
					(size 1.27 1.27)
				)
				(hide yes)
			)
		)
		(property "Value" "+3V3_AON"
			(at 217.17 26.035 0)
			(effects
				(font
					(size 1.27 1.27)
				)
			)
		)
		(property "Footprint" ""
			(at 217.17 31.75 0)
			(effects
				(font
					(size 1.27 1.27)
				)
				(hide yes)
			)
		)
		(property "Datasheet" ""
			(at 217.17 31.75 0)
			(effects
				(font
					(size 1.27 1.27)
				)
				(hide yes)
			)
		)
		(property "Description" ""
			(at 217.17 31.75 0)
			(effects
				(font
					(size 1.27 1.27)
				)
			)
		)
		(pin "1"
		)
		(instances
			(project "k410t-devboard"
				(path ""
					(reference "#PWR0475")
					(unit 1)
				)
			)
		)
	)
	(symbol
		(lib_id "antmicroResistors0402:R_0R_0402")
		(at 189.23 196.85 90)
		(unit 1)
		(exclude_from_sim no)
		(in_bom yes)
		(on_board yes)
		(dnp no)
		(fields_autoplaced yes)
		(property "Reference" "R300"
			(at 191.77 193.0399 90)
			(effects
				(font
					(size 1.27 1.27)
				)
				(justify right)
			)
		)
		(property "Value" "R_0R_0402"
			(at 201.93 176.53 0)
			(effects
				(font
					(size 1.27 1.27)
					(thickness 0.15)
				)
				(justify left bottom)
				(hide yes)
			)
		)
		(property "Footprint" "antmicro-footprints:R_0402_1005Metric"
			(at 204.47 176.53 0)
			(effects
				(font
					(size 1.27 1.27)
					(thickness 0.15)
				)
				(justify left bottom)
				(hide yes)
			)
		)
		(property "Datasheet" "https://industrial.panasonic.com/cdbs/www-data/pdf/RDA0000/AOA0000C301.pdf"
			(at 207.01 176.53 0)
			(effects
				(font
					(size 1.27 1.27)
					(thickness 0.15)
				)
				(justify left bottom)
				(hide yes)
			)
		)
		(property "Description" ""
			(at 189.23 196.85 0)
			(effects
				(font
					(size 1.27 1.27)
				)
			)
		)
		(property "Manufacturer" "Panasonic"
			(at 212.09 176.53 0)
			(effects
				(font
					(size 1.27 1.27)
					(thickness 0.15)
				)
				(justify left bottom)
				(hide yes)
			)
		)
		(property "MPN" "ERJ2GE0R00X"
			(at 209.55 176.53 0)
			(effects
				(font
					(size 1.27 1.27)
					(thickness 0.15)
				)
				(justify left bottom)
				(hide yes)
			)
		)
		(property "Val" "0R"
			(at 191.77 195.5799 90)
			(effects
				(font
					(size 1.27 1.27)
					(thickness 0.15)
				)
				(justify right)
			)
		)
		(property "License" "Apache-2.0"
			(at 214.63 176.53 0)
			(effects
				(font
					(size 1.27 1.27)
					(thickness 0.15)
				)
				(justify left bottom)
				(hide yes)
			)
		)
		(property "Author" "Antmicro"
			(at 217.17 176.53 0)
			(effects
				(font
					(size 1.27 1.27)
					(thickness 0.15)
				)
				(justify left bottom)
				(hide yes)
			)
		)
		(property "Tolerance" "~"
			(at 199.39 176.53 0)
			(effects
				(font
					(size 1.27 1.27)
				)
				(justify left bottom)
				(hide yes)
			)
		)
		(property "Current" "1A"
			(at 191.77 196.8499 90)
			(effects
				(font
					(size 1.27 1.27)
					(thickness 0.15)
				)
				(justify right)
				(hide yes)
			)
		)
		(pin "1"
		)
		(pin "2"
		)
		(instances
			(project "k410t-devboard"
				(path ""
					(reference "R300")
					(unit 1)
				)
			)
		)
	)
	(symbol
		(lib_id "antmicroCapacitors0603:C_22u_0603")
		(at 119.38 140.97 90)
		(unit 1)
		(exclude_from_sim no)
		(in_bom yes)
		(on_board yes)
		(dnp no)
		(property "Reference" "C328"
			(at 120.015 136.525 90)
			(effects
				(font
					(size 1.27 1.27)
				)
				(justify right)
			)
		)
		(property "Value" "C_22u_0603"
			(at 129.54 120.65 0)
			(effects
				(font
					(size 1.27 1.27)
					(thickness 0.15)
				)
				(justify left bottom)
				(hide yes)
			)
		)
		(property "Footprint" "antmicro-footprints:C_0603_1608Metric"
			(at 132.08 120.65 0)
			(effects
				(font
					(size 1.27 1.27)
					(thickness 0.15)
				)
				(justify left bottom)
				(hide yes)
			)
		)
		(property "Datasheet" "https://www.murata.com/products/productdetail?partno=GRM188R60J226MEA0%23"
			(at 134.62 120.65 0)
			(effects
				(font
					(size 1.27 1.27)
					(thickness 0.15)
				)
				(justify left bottom)
				(hide yes)
			)
		)
		(property "Description" ""
			(at 119.38 140.97 0)
			(effects
				(font
					(size 1.27 1.27)
				)
			)
		)
		(property "Manufacturer" "Murata"
			(at 139.7 120.65 0)
			(effects
				(font
					(size 1.27 1.27)
					(thickness 0.15)
				)
				(justify left bottom)
				(hide yes)
			)
		)
		(property "MPN" "GRM188R60J226MEA0D"
			(at 137.16 120.65 0)
			(effects
				(font
					(size 1.27 1.27)
					(thickness 0.15)
				)
				(justify left bottom)
				(hide yes)
			)
		)
		(property "Val" "22u"
			(at 120.015 140.335 90)
			(effects
				(font
					(size 1.27 1.27)
					(thickness 0.15)
				)
				(justify right)
			)
		)
		(property "License" "Apache-2.0"
			(at 142.24 120.65 0)
			(effects
				(font
					(size 1.27 1.27)
					(thickness 0.15)
				)
				(justify left bottom)
				(hide yes)
			)
		)
		(property "Author" "Antmicro"
			(at 144.78 120.65 0)
			(effects
				(font
					(size 1.27 1.27)
					(thickness 0.15)
				)
				(justify left bottom)
				(hide yes)
			)
		)
		(property "Voltage" ""
			(at 147.32 120.65 0)
			(effects
				(font
					(size 1.27 1.27)
				)
				(justify left bottom)
				(hide yes)
			)
		)
		(property "Dielectric" ""
			(at 149.86 120.65 0)
			(effects
				(font
					(size 1.27 1.27)
				)
				(justify left bottom)
				(hide yes)
			)
		)
		(pin "1"
		)
		(pin "2"
		)
		(instances
			(project "k410t-devboard"
				(path ""
					(reference "C328")
					(unit 1)
				)
			)
		)
	)
	(symbol
		(lib_id "antmicroResistors0603:R_0R_22.4A_0603")
		(at 124.46 93.98 0)
		(unit 1)
		(exclude_from_sim no)
		(in_bom yes)
		(on_board yes)
		(dnp no)
		(property "Reference" "R285"
			(at 127 86.36 0)
			(effects
				(font
					(size 1.27 1.27)
				)
			)
		)
		(property "Value" "R_0R_22.4A_0603"
			(at 127 87.63 0)
			(effects
				(font
					(size 1.27 1.27)
					(thickness 0.15)
				)
				(hide yes)
			)
		)
		(property "Footprint" "antmicro-footprints:R_0603_1608Metric"
			(at 147.32 106.68 0)
			(effects
				(font
					(size 1.27 1.27)
					(thickness 0.15)
				)
				(justify left bottom)
				(hide yes)
			)
		)
		(property "Datasheet" "https://fscdn.rohm.com/en/products/databook/datasheet/passive/resistor/chip_resistor/pmr-jpw-e.pdf"
			(at 147.32 109.22 0)
			(effects
				(font
					(size 1.27 1.27)
					(thickness 0.15)
				)
				(justify left bottom)
				(hide yes)
			)
		)
		(property "Description" ""
			(at 124.46 93.98 0)
			(effects
				(font
					(size 1.27 1.27)
				)
			)
		)
		(property "Manufacturer" "ROHM Semiconductor"
			(at 147.32 111.76 0)
			(effects
				(font
					(size 1.27 1.27)
					(thickness 0.15)
				)
				(justify left bottom)
				(hide yes)
			)
		)
		(property "MPN" "PMR03EZPJ000"
			(at 147.32 114.3 0)
			(effects
				(font
					(size 1.27 1.27)
					(thickness 0.15)
				)
				(justify left bottom)
				(hide yes)
			)
		)
		(property "Val" "0R"
			(at 127 88.9 0)
			(effects
				(font
					(size 1.27 1.27)
					(thickness 0.15)
				)
			)
		)
		(property "Author" "Antmicro"
			(at 147.32 116.84 0)
			(effects
				(font
					(size 1.27 1.27)
					(thickness 0.15)
				)
				(justify left bottom)
				(hide yes)
			)
		)
		(property "License" "Apache-2.0"
			(at 147.32 119.38 0)
			(effects
				(font
					(size 1.27 1.27)
					(thickness 0.15)
				)
				(justify left bottom)
				(hide yes)
			)
		)
		(property "Max. Curr." "22.4A"
			(at 127 91.44 0)
			(effects
				(font
					(size 1.27 1.27)
					(thickness 0.15)
				)
			)
		)
		(property "Tolerance" "template_tolerance"
			(at 144.78 104.14 0)
			(effects
				(font
					(size 1.27 1.27)
				)
				(justify left bottom)
				(hide yes)
			)
		)
		(pin "1"
		)
		(pin "2"
		)
		(instances
			(project "k410t-devboard"
				(path ""
					(reference "R285")
					(unit 1)
				)
			)
		)
	)
	(symbol
		(lib_id "antmicroCapacitors0603:C_22u_0603")
		(at 110.49 101.6 90)
		(unit 1)
		(exclude_from_sim no)
		(in_bom yes)
		(on_board yes)
		(dnp no)
		(property "Reference" "C322"
			(at 111.125 97.155 90)
			(effects
				(font
					(size 1.27 1.27)
				)
				(justify right)
			)
		)
		(property "Value" "C_22u_0603"
			(at 120.65 81.28 0)
			(effects
				(font
					(size 1.27 1.27)
					(thickness 0.15)
				)
				(justify left bottom)
				(hide yes)
			)
		)
		(property "Footprint" "antmicro-footprints:C_0603_1608Metric"
			(at 123.19 81.28 0)
			(effects
				(font
					(size 1.27 1.27)
					(thickness 0.15)
				)
				(justify left bottom)
				(hide yes)
			)
		)
		(property "Datasheet" "https://www.murata.com/products/productdetail?partno=GRM188R60J226MEA0%23"
			(at 125.73 81.28 0)
			(effects
				(font
					(size 1.27 1.27)
					(thickness 0.15)
				)
				(justify left bottom)
				(hide yes)
			)
		)
		(property "Description" ""
			(at 110.49 101.6 0)
			(effects
				(font
					(size 1.27 1.27)
				)
			)
		)
		(property "Manufacturer" "Murata"
			(at 130.81 81.28 0)
			(effects
				(font
					(size 1.27 1.27)
					(thickness 0.15)
				)
				(justify left bottom)
				(hide yes)
			)
		)
		(property "MPN" "GRM188R60J226MEA0D"
			(at 128.27 81.28 0)
			(effects
				(font
					(size 1.27 1.27)
					(thickness 0.15)
				)
				(justify left bottom)
				(hide yes)
			)
		)
		(property "Val" "22u"
			(at 111.125 100.965 90)
			(effects
				(font
					(size 1.27 1.27)
					(thickness 0.15)
				)
				(justify right)
			)
		)
		(property "License" "Apache-2.0"
			(at 133.35 81.28 0)
			(effects
				(font
					(size 1.27 1.27)
					(thickness 0.15)
				)
				(justify left bottom)
				(hide yes)
			)
		)
		(property "Author" "Antmicro"
			(at 135.89 81.28 0)
			(effects
				(font
					(size 1.27 1.27)
					(thickness 0.15)
				)
				(justify left bottom)
				(hide yes)
			)
		)
		(property "Voltage" ""
			(at 138.43 81.28 0)
			(effects
				(font
					(size 1.27 1.27)
				)
				(justify left bottom)
				(hide yes)
			)
		)
		(property "Dielectric" ""
			(at 140.97 81.28 0)
			(effects
				(font
					(size 1.27 1.27)
				)
				(justify left bottom)
				(hide yes)
			)
		)
		(pin "1"
		)
		(pin "2"
		)
		(instances
			(project "k410t-devboard"
				(path ""
					(reference "C322")
					(unit 1)
				)
			)
		)
	)
	(symbol
		(lib_id "antmicropower:GND")
		(at 337.82 240.03 0)
		(unit 1)
		(exclude_from_sim no)
		(in_bom yes)
		(on_board yes)
		(dnp no)
		(fields_autoplaced yes)
		(property "Reference" "#PWR0426"
			(at 337.82 246.38 0)
			(effects
				(font
					(size 1.27 1.27)
				)
				(hide yes)
			)
		)
		(property "Value" "GND"
			(at 337.82 243.84 0)
			(effects
				(font
					(size 1.27 1.27)
				)
			)
		)
		(property "Footprint" ""
			(at 346.71 247.65 0)
			(effects
				(font
					(size 1.27 1.27)
					(thickness 0.15)
				)
				(justify left bottom)
				(hide yes)
			)
		)
		(property "Datasheet" ""
			(at 346.71 252.73 0)
			(effects
				(font
					(size 1.27 1.27)
					(thickness 0.15)
				)
				(justify left bottom)
				(hide yes)
			)
		)
		(property "Description" ""
			(at 337.82 240.03 0)
			(effects
				(font
					(size 1.27 1.27)
				)
			)
		)
		(property "Author" "Antmicro"
			(at 346.71 247.65 0)
			(effects
				(font
					(size 1.27 1.27)
					(thickness 0.15)
				)
				(justify left bottom)
				(hide yes)
			)
		)
		(property "License" "Apache-2.0"
			(at 346.71 250.19 0)
			(effects
				(font
					(size 1.27 1.27)
					(thickness 0.15)
				)
				(justify left bottom)
				(hide yes)
			)
		)
		(pin "1"
		)
		(instances
			(project "k410t-devboard"
				(path ""
					(reference "#PWR0426")
					(unit 1)
				)
			)
		)
	)
	(symbol
		(lib_id "antmicroPMICVoltageRegulatorsDCDCSwitchingRegulators:MP8869S")
		(at 328.93 40.64 0)
		(unit 1)
		(exclude_from_sim no)
		(in_bom yes)
		(on_board yes)
		(dnp no)
		(property "Reference" "U37"
			(at 331.47 73.66 0)
			(effects
				(font
					(size 1.27 1.27)
				)
				(justify left)
			)
		)
		(property "Value" "MP8869S"
			(at 331.47 73.025 0)
			(effects
				(font
					(size 1.27 1.27)
					(thickness 0.15)
				)
				(justify left)
				(hide yes)
			)
		)
		(property "Footprint" "antmicro-footprints:MPS_QFN-14_MP8869S"
			(at 354.33 52.07 0)
			(effects
				(font
					(size 1.27 1.27)
					(thickness 0.15)
				)
				(justify left bottom)
				(hide yes)
			)
		)
		(property "Datasheet" "https://www.mouser.com/datasheet/2/277/MP8869S-2946178.pdf"
			(at 354.33 54.61 0)
			(effects
				(font
					(size 1.27 1.27)
					(thickness 0.15)
				)
				(justify left bottom)
				(hide yes)
			)
		)
		(property "Description" ""
			(at 328.93 40.64 0)
			(effects
				(font
					(size 1.27 1.27)
				)
			)
		)
		(property "MPN" "MP8869SGL-P"
			(at 331.47 76.2 0)
			(effects
				(font
					(size 1.27 1.27)
					(thickness 0.15)
				)
				(justify left)
			)
		)
		(property "Manufacturer" "Monolithic Power Systems"
			(at 354.33 59.69 0)
			(effects
				(font
					(size 1.27 1.27)
					(thickness 0.15)
				)
				(justify left bottom)
				(hide yes)
			)
		)
		(property "Author" "Antmicro"
			(at 354.33 62.23 0)
			(effects
				(font
					(size 1.27 1.27)
					(thickness 0.15)
				)
				(justify left bottom)
				(hide yes)
			)
		)
		(property "License" "Apache-2.0"
			(at 354.33 64.77 0)
			(effects
				(font
					(size 1.27 1.27)
					(thickness 0.15)
				)
				(justify left bottom)
				(hide yes)
			)
		)
		(pin "1"
		)
		(pin "10"
		)
		(pin "11"
		)
		(pin "12"
		)
		(pin "13"
		)
		(pin "14"
		)
		(pin "2"
		)
		(pin "3"
		)
		(pin "4"
		)
		(pin "5"
		)
		(pin "6"
		)
		(pin "7"
		)
		(pin "8"
		)
		(pin "9"
		)
		(instances
			(project "k410t-devboard"
				(path ""
					(reference "U37")
					(unit 1)
				)
			)
		)
	)
	(symbol
		(lib_id "antmicroCapacitors0402:C_1n_0402")
		(at 312.42 237.49 90)
		(unit 1)
		(exclude_from_sim no)
		(in_bom yes)
		(on_board yes)
		(dnp no)
		(property "Reference" "C350"
			(at 313.055 233.045 90)
			(effects
				(font
					(size 1.27 1.27)
				)
				(justify right)
			)
		)
		(property "Value" "C_1n_0402"
			(at 322.58 217.17 0)
			(effects
				(font
					(size 1.27 1.27)
					(thickness 0.15)
				)
				(justify left bottom)
				(hide yes)
			)
		)
		(property "Footprint" "antmicro-footprints:C_0402_1005Metric"
			(at 325.12 217.17 0)
			(effects
				(font
					(size 1.27 1.27)
					(thickness 0.15)
				)
				(justify left bottom)
				(hide yes)
			)
		)
		(property "Datasheet" "https://www.murata.com/products/productdetail?partno=GRM1555C1H102JA01%23"
			(at 327.66 217.17 0)
			(effects
				(font
					(size 1.27 1.27)
					(thickness 0.15)
				)
				(justify left bottom)
				(hide yes)
			)
		)
		(property "Description" ""
			(at 312.42 237.49 0)
			(effects
				(font
					(size 1.27 1.27)
				)
			)
		)
		(property "Manufacturer" "Murata"
			(at 332.74 217.17 0)
			(effects
				(font
					(size 1.27 1.27)
					(thickness 0.15)
				)
				(justify left bottom)
				(hide yes)
			)
		)
		(property "MPN" "GRM1555C1H102JA01D"
			(at 330.2 217.17 0)
			(effects
				(font
					(size 1.27 1.27)
					(thickness 0.15)
				)
				(justify left bottom)
				(hide yes)
			)
		)
		(property "Val" "1n"
			(at 313.055 236.855 90)
			(effects
				(font
					(size 1.27 1.27)
					(thickness 0.15)
				)
				(justify right)
			)
		)
		(property "License" "Apache-2.0"
			(at 335.28 217.17 0)
			(effects
				(font
					(size 1.27 1.27)
					(thickness 0.15)
				)
				(justify left bottom)
				(hide yes)
			)
		)
		(property "Author" "Antmicro"
			(at 337.82 217.17 0)
			(effects
				(font
					(size 1.27 1.27)
					(thickness 0.15)
				)
				(justify left bottom)
				(hide yes)
			)
		)
		(property "Voltage" "50V"
			(at 340.36 217.17 0)
			(effects
				(font
					(size 1.27 1.27)
				)
				(justify left bottom)
				(hide yes)
			)
		)
		(property "Dielectric" "C0G"
			(at 342.9 217.17 0)
			(effects
				(font
					(size 1.27 1.27)
				)
				(justify left bottom)
				(hide yes)
			)
		)
		(pin "1"
		)
		(pin "2"
		)
		(instances
			(project "k410t-devboard"
				(path ""
					(reference "C350")
					(unit 1)
				)
			)
		)
	)
	(symbol
		(lib_id "k410t-devboard:Net-Tie_2")
		(at 391.16 165.1 0)
		(unit 1)
		(exclude_from_sim no)
		(in_bom yes)
		(on_board yes)
		(dnp no)
		(fields_autoplaced yes)
		(property "Reference" "NT2"
			(at 391.16 163.83 0)
			(effects
				(font
					(size 1.27 1.27)
				)
				(hide yes)
			)
		)
		(property "Value" "Net-Tie_2"
			(at 393.065 161.925 0)
			(effects
				(font
					(size 1.27 1.27)
					(thickness 0.15)
				)
				(hide yes)
			)
		)
		(property "Footprint" "antmicro-footprints:NetTie-2_SMD_Pad0.127mm"
			(at 412.75 170.18 0)
			(effects
				(font
					(size 1.27 1.27)
					(thickness 0.15)
				)
				(justify left bottom)
				(hide yes)
			)
		)
		(property "Datasheet" ""
			(at 412.75 172.72 0)
			(effects
				(font
					(size 1.27 1.27)
					(thickness 0.15)
				)
				(justify left bottom)
				(hide yes)
			)
		)
		(property "Description" ""
			(at 391.16 165.1 0)
			(effects
				(font
					(size 1.27 1.27)
				)
			)
		)
		(property "MPN" ""
			(at 412.75 173.99 0)
			(effects
				(font
					(size 1.27 1.27)
				)
				(justify left)
				(hide yes)
			)
		)
		(property "Manufacturer" ""
			(at 412.75 176.53 0)
			(effects
				(font
					(size 1.27 1.27)
				)
				(justify left)
				(hide yes)
			)
		)
		(property "Author" "Antmicro"
			(at 412.75 180.34 0)
			(effects
				(font
					(size 1.27 1.27)
					(thickness 0.15)
				)
				(justify left bottom)
				(hide yes)
			)
		)
		(property "License" "Apache-2.0"
			(at 412.75 182.88 0)
			(effects
				(font
					(size 1.27 1.27)
					(thickness 0.15)
				)
				(justify left bottom)
				(hide yes)
			)
		)
		(pin "1"
		)
		(pin "2"
		)
		(instances
			(project "k410t-devboard"
				(path ""
					(reference "NT2")
					(unit 1)
				)
			)
		)
	)
	(symbol
		(lib_id "antmicroCapacitors0603:C_22u_0603")
		(at 363.22 53.34 90)
		(unit 1)
		(exclude_from_sim no)
		(in_bom yes)
		(on_board yes)
		(dnp no)
		(property "Reference" "C359"
			(at 363.855 48.895 90)
			(effects
				(font
					(size 1.27 1.27)
				)
				(justify right)
			)
		)
		(property "Value" "C_22u_0603"
			(at 373.38 33.02 0)
			(effects
				(font
					(size 1.27 1.27)
					(thickness 0.15)
				)
				(justify left bottom)
				(hide yes)
			)
		)
		(property "Footprint" "antmicro-footprints:C_0603_1608Metric"
			(at 375.92 33.02 0)
			(effects
				(font
					(size 1.27 1.27)
					(thickness 0.15)
				)
				(justify left bottom)
				(hide yes)
			)
		)
		(property "Datasheet" "https://www.murata.com/products/productdetail?partno=GRM188R60J226MEA0%23"
			(at 378.46 33.02 0)
			(effects
				(font
					(size 1.27 1.27)
					(thickness 0.15)
				)
				(justify left bottom)
				(hide yes)
			)
		)
		(property "Description" ""
			(at 363.22 53.34 0)
			(effects
				(font
					(size 1.27 1.27)
				)
			)
		)
		(property "Manufacturer" "Murata"
			(at 383.54 33.02 0)
			(effects
				(font
					(size 1.27 1.27)
					(thickness 0.15)
				)
				(justify left bottom)
				(hide yes)
			)
		)
		(property "MPN" "GRM188R60J226MEA0D"
			(at 381 33.02 0)
			(effects
				(font
					(size 1.27 1.27)
					(thickness 0.15)
				)
				(justify left bottom)
				(hide yes)
			)
		)
		(property "Val" "22u"
			(at 363.855 52.705 90)
			(effects
				(font
					(size 1.27 1.27)
					(thickness 0.15)
				)
				(justify right)
			)
		)
		(property "License" "Apache-2.0"
			(at 386.08 33.02 0)
			(effects
				(font
					(size 1.27 1.27)
					(thickness 0.15)
				)
				(justify left bottom)
				(hide yes)
			)
		)
		(property "Author" "Antmicro"
			(at 388.62 33.02 0)
			(effects
				(font
					(size 1.27 1.27)
					(thickness 0.15)
				)
				(justify left bottom)
				(hide yes)
			)
		)
		(property "Voltage" ""
			(at 391.16 33.02 0)
			(effects
				(font
					(size 1.27 1.27)
				)
				(justify left bottom)
				(hide yes)
			)
		)
		(property "Dielectric" ""
			(at 393.7 33.02 0)
			(effects
				(font
					(size 1.27 1.27)
				)
				(justify left bottom)
				(hide yes)
			)
		)
		(pin "1"
		)
		(pin "2"
		)
		(instances
			(project "k410t-devboard"
				(path ""
					(reference "C359")
					(unit 1)
				)
			)
		)
	)
	(symbol
		(lib_id "antmicropower:GND")
		(at 377.19 173.99 0)
		(unit 1)
		(exclude_from_sim no)
		(in_bom yes)
		(on_board yes)
		(dnp no)
		(fields_autoplaced yes)
		(property "Reference" "#PWR0451"
			(at 377.19 180.34 0)
			(effects
				(font
					(size 1.27 1.27)
				)
				(hide yes)
			)
		)
		(property "Value" "GND"
			(at 377.19 177.8 0)
			(effects
				(font
					(size 1.27 1.27)
				)
			)
		)
		(property "Footprint" ""
			(at 386.08 181.61 0)
			(effects
				(font
					(size 1.27 1.27)
					(thickness 0.15)
				)
				(justify left bottom)
				(hide yes)
			)
		)
		(property "Datasheet" ""
			(at 386.08 186.69 0)
			(effects
				(font
					(size 1.27 1.27)
					(thickness 0.15)
				)
				(justify left bottom)
				(hide yes)
			)
		)
		(property "Description" ""
			(at 377.19 173.99 0)
			(effects
				(font
					(size 1.27 1.27)
				)
			)
		)
		(property "Author" "Antmicro"
			(at 386.08 181.61 0)
			(effects
				(font
					(size 1.27 1.27)
					(thickness 0.15)
				)
				(justify left bottom)
				(hide yes)
			)
		)
		(property "License" "Apache-2.0"
			(at 386.08 184.15 0)
			(effects
				(font
					(size 1.27 1.27)
					(thickness 0.15)
				)
				(justify left bottom)
				(hide yes)
			)
		)
		(pin "1"
		)
		(instances
			(project "k410t-devboard"
				(path ""
					(reference "#PWR0451")
					(unit 1)
				)
			)
		)
	)
	(symbol
		(lib_id "antmicroCapacitors0603:C_22u_0603")
		(at 110.49 212.09 90)
		(unit 1)
		(exclude_from_sim no)
		(in_bom yes)
		(on_board yes)
		(dnp no)
		(property "Reference" "C325"
			(at 111.125 207.645 90)
			(effects
				(font
					(size 1.27 1.27)
				)
				(justify right)
			)
		)
		(property "Value" "C_22u_0603"
			(at 120.65 191.77 0)
			(effects
				(font
					(size 1.27 1.27)
					(thickness 0.15)
				)
				(justify left bottom)
				(hide yes)
			)
		)
		(property "Footprint" "antmicro-footprints:C_0603_1608Metric"
			(at 123.19 191.77 0)
			(effects
				(font
					(size 1.27 1.27)
					(thickness 0.15)
				)
				(justify left bottom)
				(hide yes)
			)
		)
		(property "Datasheet" "https://www.murata.com/products/productdetail?partno=GRM188R60J226MEA0%23"
			(at 125.73 191.77 0)
			(effects
				(font
					(size 1.27 1.27)
					(thickness 0.15)
				)
				(justify left bottom)
				(hide yes)
			)
		)
		(property "Description" ""
			(at 110.49 212.09 0)
			(effects
				(font
					(size 1.27 1.27)
				)
			)
		)
		(property "Manufacturer" "Murata"
			(at 130.81 191.77 0)
			(effects
				(font
					(size 1.27 1.27)
					(thickness 0.15)
				)
				(justify left bottom)
				(hide yes)
			)
		)
		(property "MPN" "GRM188R60J226MEA0D"
			(at 128.27 191.77 0)
			(effects
				(font
					(size 1.27 1.27)
					(thickness 0.15)
				)
				(justify left bottom)
				(hide yes)
			)
		)
		(property "Val" "22u"
			(at 111.125 211.455 90)
			(effects
				(font
					(size 1.27 1.27)
					(thickness 0.15)
				)
				(justify right)
			)
		)
		(property "License" "Apache-2.0"
			(at 133.35 191.77 0)
			(effects
				(font
					(size 1.27 1.27)
					(thickness 0.15)
				)
				(justify left bottom)
				(hide yes)
			)
		)
		(property "Author" "Antmicro"
			(at 135.89 191.77 0)
			(effects
				(font
					(size 1.27 1.27)
					(thickness 0.15)
				)
				(justify left bottom)
				(hide yes)
			)
		)
		(property "Voltage" ""
			(at 138.43 191.77 0)
			(effects
				(font
					(size 1.27 1.27)
				)
				(justify left bottom)
				(hide yes)
			)
		)
		(property "Dielectric" ""
			(at 140.97 191.77 0)
			(effects
				(font
					(size 1.27 1.27)
				)
				(justify left bottom)
				(hide yes)
			)
		)
		(pin "1"
		)
		(pin "2"
		)
		(instances
			(project "k410t-devboard"
				(path ""
					(reference "C325")
					(unit 1)
				)
			)
		)
	)
	(symbol
		(lib_id "antmicropower:GND")
		(at 49.53 121.92 0)
		(unit 1)
		(exclude_from_sim no)
		(in_bom yes)
		(on_board yes)
		(dnp no)
		(fields_autoplaced yes)
		(property "Reference" "#PWR0362"
			(at 49.53 128.27 0)
			(effects
				(font
					(size 1.27 1.27)
				)
				(hide yes)
			)
		)
		(property "Value" "GND"
			(at 49.53 125.73 0)
			(effects
				(font
					(size 1.27 1.27)
				)
			)
		)
		(property "Footprint" ""
			(at 58.42 129.54 0)
			(effects
				(font
					(size 1.27 1.27)
					(thickness 0.15)
				)
				(justify left bottom)
				(hide yes)
			)
		)
		(property "Datasheet" ""
			(at 58.42 134.62 0)
			(effects
				(font
					(size 1.27 1.27)
					(thickness 0.15)
				)
				(justify left bottom)
				(hide yes)
			)
		)
		(property "Description" ""
			(at 49.53 121.92 0)
			(effects
				(font
					(size 1.27 1.27)
				)
			)
		)
		(property "Author" "Antmicro"
			(at 58.42 129.54 0)
			(effects
				(font
					(size 1.27 1.27)
					(thickness 0.15)
				)
				(justify left bottom)
				(hide yes)
			)
		)
		(property "License" "Apache-2.0"
			(at 58.42 132.08 0)
			(effects
				(font
					(size 1.27 1.27)
					(thickness 0.15)
				)
				(justify left bottom)
				(hide yes)
			)
		)
		(pin "1"
		)
		(instances
			(project "k410t-devboard"
				(path ""
					(reference "#PWR0362")
					(unit 1)
				)
			)
		)
	)
	(symbol
		(lib_id "antmicropower:GND")
		(at 21.59 53.34 0)
		(unit 1)
		(exclude_from_sim no)
		(in_bom yes)
		(on_board yes)
		(dnp no)
		(property "Reference" "#PWR0359"
			(at 21.59 59.69 0)
			(effects
				(font
					(size 1.27 1.27)
				)
				(hide yes)
			)
		)
		(property "Value" "GND"
			(at 21.59 57.15 0)
			(effects
				(font
					(size 1.27 1.27)
				)
			)
		)
		(property "Footprint" ""
			(at 30.48 60.96 0)
			(effects
				(font
					(size 1.27 1.27)
					(thickness 0.15)
				)
				(justify left bottom)
				(hide yes)
			)
		)
		(property "Datasheet" ""
			(at 30.48 66.04 0)
			(effects
				(font
					(size 1.27 1.27)
					(thickness 0.15)
				)
				(justify left bottom)
				(hide yes)
			)
		)
		(property "Description" ""
			(at 21.59 53.34 0)
			(effects
				(font
					(size 1.27 1.27)
				)
			)
		)
		(property "Author" "Antmicro"
			(at 30.48 60.96 0)
			(effects
				(font
					(size 1.27 1.27)
					(thickness 0.15)
				)
				(justify left bottom)
				(hide yes)
			)
		)
		(property "License" "Apache-2.0"
			(at 30.48 63.5 0)
			(effects
				(font
					(size 1.27 1.27)
					(thickness 0.15)
				)
				(justify left bottom)
				(hide yes)
			)
		)
		(pin "1"
		)
		(instances
			(project "k410t-devboard"
				(path ""
					(reference "#PWR0359")
					(unit 1)
				)
			)
		)
	)
	(symbol
		(lib_id "k410t-devboard:Net-Tie_2")
		(at 203.2 186.69 90)
		(unit 1)
		(exclude_from_sim no)
		(in_bom yes)
		(on_board yes)
		(dnp no)
		(fields_autoplaced yes)
		(property "Reference" "NT31"
			(at 201.93 186.69 0)
			(effects
				(font
					(size 1.27 1.27)
				)
				(hide yes)
			)
		)
		(property "Value" "Net-Tie_2"
			(at 204.47 184.7849 90)
			(effects
				(font
					(size 1.27 1.27)
					(thickness 0.15)
				)
				(justify right)
				(hide yes)
			)
		)
		(property "Footprint" "antmicro-footprints:NetTie-2_SMD_Pad0.127mm"
			(at 208.28 165.1 0)
			(effects
				(font
					(size 1.27 1.27)
					(thickness 0.15)
				)
				(justify left bottom)
				(hide yes)
			)
		)
		(property "Datasheet" ""
			(at 210.82 165.1 0)
			(effects
				(font
					(size 1.27 1.27)
					(thickness 0.15)
				)
				(justify left bottom)
				(hide yes)
			)
		)
		(property "Description" ""
			(at 203.2 186.69 0)
			(effects
				(font
					(size 1.27 1.27)
				)
			)
		)
		(property "MPN" ""
			(at 212.09 165.1 0)
			(effects
				(font
					(size 1.27 1.27)
				)
				(justify left)
				(hide yes)
			)
		)
		(property "Manufacturer" ""
			(at 214.63 165.1 0)
			(effects
				(font
					(size 1.27 1.27)
				)
				(justify left)
				(hide yes)
			)
		)
		(property "Author" "Antmicro"
			(at 218.44 165.1 0)
			(effects
				(font
					(size 1.27 1.27)
					(thickness 0.15)
				)
				(justify left bottom)
				(hide yes)
			)
		)
		(property "License" "Apache-2.0"
			(at 220.98 165.1 0)
			(effects
				(font
					(size 1.27 1.27)
					(thickness 0.15)
				)
				(justify left bottom)
				(hide yes)
			)
		)
		(pin "1"
		)
		(pin "2"
		)
		(instances
			(project "k410t-devboard"
				(path ""
					(reference "NT31")
					(unit 1)
				)
			)
		)
	)
	(symbol
		(lib_id "antmicropower:GND")
		(at 81.28 48.26 0)
		(unit 1)
		(exclude_from_sim no)
		(in_bom yes)
		(on_board yes)
		(dnp no)
		(property "Reference" "#PWR0366"
			(at 81.28 54.61 0)
			(effects
				(font
					(size 1.27 1.27)
				)
				(hide yes)
			)
		)
		(property "Value" "GND"
			(at 81.28 52.07 0)
			(effects
				(font
					(size 1.27 1.27)
				)
			)
		)
		(property "Footprint" ""
			(at 90.17 55.88 0)
			(effects
				(font
					(size 1.27 1.27)
					(thickness 0.15)
				)
				(justify left bottom)
				(hide yes)
			)
		)
		(property "Datasheet" ""
			(at 90.17 60.96 0)
			(effects
				(font
					(size 1.27 1.27)
					(thickness 0.15)
				)
				(justify left bottom)
				(hide yes)
			)
		)
		(property "Description" ""
			(at 81.28 48.26 0)
			(effects
				(font
					(size 1.27 1.27)
				)
			)
		)
		(property "Author" "Antmicro"
			(at 90.17 55.88 0)
			(effects
				(font
					(size 1.27 1.27)
					(thickness 0.15)
				)
				(justify left bottom)
				(hide yes)
			)
		)
		(property "License" "Apache-2.0"
			(at 90.17 58.42 0)
			(effects
				(font
					(size 1.27 1.27)
					(thickness 0.15)
				)
				(justify left bottom)
				(hide yes)
			)
		)
		(pin "1"
		)
		(instances
			(project "k410t-devboard"
				(path ""
					(reference "#PWR0366")
					(unit 1)
				)
			)
		)
	)
	(symbol
		(lib_id "antmicroCapacitors0603:C_22u_0603")
		(at 379.73 53.34 90)
		(unit 1)
		(exclude_from_sim no)
		(in_bom yes)
		(on_board yes)
		(dnp no)
		(property "Reference" "C363"
			(at 380.365 48.895 90)
			(effects
				(font
					(size 1.27 1.27)
				)
				(justify right)
			)
		)
		(property "Value" "C_22u_0603"
			(at 389.89 33.02 0)
			(effects
				(font
					(size 1.27 1.27)
					(thickness 0.15)
				)
				(justify left bottom)
				(hide yes)
			)
		)
		(property "Footprint" "antmicro-footprints:C_0603_1608Metric"
			(at 392.43 33.02 0)
			(effects
				(font
					(size 1.27 1.27)
					(thickness 0.15)
				)
				(justify left bottom)
				(hide yes)
			)
		)
		(property "Datasheet" "https://www.murata.com/products/productdetail?partno=GRM188R60J226MEA0%23"
			(at 394.97 33.02 0)
			(effects
				(font
					(size 1.27 1.27)
					(thickness 0.15)
				)
				(justify left bottom)
				(hide yes)
			)
		)
		(property "Description" ""
			(at 379.73 53.34 0)
			(effects
				(font
					(size 1.27 1.27)
				)
			)
		)
		(property "Manufacturer" "Murata"
			(at 400.05 33.02 0)
			(effects
				(font
					(size 1.27 1.27)
					(thickness 0.15)
				)
				(justify left bottom)
				(hide yes)
			)
		)
		(property "MPN" "GRM188R60J226MEA0D"
			(at 397.51 33.02 0)
			(effects
				(font
					(size 1.27 1.27)
					(thickness 0.15)
				)
				(justify left bottom)
				(hide yes)
			)
		)
		(property "Val" "22u"
			(at 380.365 52.705 90)
			(effects
				(font
					(size 1.27 1.27)
					(thickness 0.15)
				)
				(justify right)
			)
		)
		(property "License" "Apache-2.0"
			(at 402.59 33.02 0)
			(effects
				(font
					(size 1.27 1.27)
					(thickness 0.15)
				)
				(justify left bottom)
				(hide yes)
			)
		)
		(property "Author" "Antmicro"
			(at 405.13 33.02 0)
			(effects
				(font
					(size 1.27 1.27)
					(thickness 0.15)
				)
				(justify left bottom)
				(hide yes)
			)
		)
		(property "Voltage" ""
			(at 407.67 33.02 0)
			(effects
				(font
					(size 1.27 1.27)
				)
				(justify left bottom)
				(hide yes)
			)
		)
		(property "Dielectric" ""
			(at 410.21 33.02 0)
			(effects
				(font
					(size 1.27 1.27)
				)
				(justify left bottom)
				(hide yes)
			)
		)
		(pin "1"
		)
		(pin "2"
		)
		(instances
			(project "k410t-devboard"
				(path ""
					(reference "C363")
					(unit 1)
				)
			)
		)
	)
	(symbol
		(lib_id "antmicropower:+3.3V")
		(at 204.47 223.52 0)
		(unit 1)
		(exclude_from_sim no)
		(in_bom yes)
		(on_board yes)
		(dnp no)
		(fields_autoplaced yes)
		(property "Reference" "#PWR0371"
			(at 204.47 227.33 0)
			(effects
				(font
					(size 1.27 1.27)
				)
				(hide yes)
			)
		)
		(property "Value" "+3V3"
			(at 204.47 219.964 0)
			(effects
				(font
					(size 1.27 1.27)
				)
			)
		)
		(property "Footprint" ""
			(at 204.47 223.52 0)
			(effects
				(font
					(size 1.27 1.27)
				)
				(hide yes)
			)
		)
		(property "Datasheet" ""
			(at 204.47 223.52 0)
			(effects
				(font
					(size 1.27 1.27)
				)
				(hide yes)
			)
		)
		(property "Description" ""
			(at 204.47 223.52 0)
			(effects
				(font
					(size 1.27 1.27)
				)
			)
		)
		(pin "1"
		)
		(instances
			(project "k410t-devboard"
				(path ""
					(reference "#PWR0371")
					(unit 1)
				)
			)
		)
	)
	(symbol
		(lib_id "antmicropower:+1V35")
		(at 401.32 207.01 0)
		(unit 1)
		(exclude_from_sim no)
		(in_bom yes)
		(on_board yes)
		(dnp no)
		(property "Reference" "#PWR0501"
			(at 401.32 210.82 0)
			(effects
				(font
					(size 1.27 1.27)
				)
				(hide yes)
			)
		)
		(property "Value" "+1V35"
			(at 401.32 203.454 0)
			(effects
				(font
					(size 1.27 1.27)
				)
			)
		)
		(property "Footprint" ""
			(at 401.32 207.01 0)
			(effects
				(font
					(size 1.27 1.27)
				)
				(hide yes)
			)
		)
		(property "Datasheet" ""
			(at 401.32 207.01 0)
			(effects
				(font
					(size 1.27 1.27)
				)
				(hide yes)
			)
		)
		(property "Description" ""
			(at 401.32 207.01 0)
			(effects
				(font
					(size 1.27 1.27)
				)
			)
		)
		(pin "1"
		)
		(instances
			(project "k410t-devboard"
				(path ""
					(reference "#PWR0501")
					(unit 1)
				)
			)
		)
	)
	(symbol
		(lib_id "antmicroTestPoints:TP_0.75mm_SMD")
		(at 71.12 218.44 90)
		(unit 1)
		(exclude_from_sim no)
		(in_bom yes)
		(on_board yes)
		(dnp no)
		(property "Reference" "TP7"
			(at 73.025 213.36 90)
			(effects
				(font
					(size 1.27 1.27)
				)
				(justify left)
			)
		)
		(property "Value" "TP_0.75mm_SMD"
			(at 73.66 218.44 0)
			(effects
				(font
					(size 1.27 1.27)
				)
				(hide yes)
			)
		)
		(property "Footprint" "antmicro-footprints:TP_SMD_0.75mm"
			(at 66.04 213.36 0)
			(effects
				(font
					(size 1.27 1.27)
				)
				(justify left)
				(hide yes)
			)
		)
		(property "Datasheet" ""
			(at 63.5 213.36 0)
			(effects
				(font
					(size 1.27 1.27)
				)
				(justify left)
				(hide yes)
			)
		)
		(property "Description" ""
			(at 71.12 218.44 0)
			(effects
				(font
					(size 1.27 1.27)
				)
			)
		)
		(property "MPN" ""
			(at 71.12 218.44 0)
			(effects
				(font
					(size 1.27 1.27)
				)
				(hide yes)
			)
		)
		(property "Manufacturer" ""
			(at 71.12 218.44 0)
			(effects
				(font
					(size 1.27 1.27)
				)
				(hide yes)
			)
		)
		(property "Author" "Antmicro"
			(at 86.36 203.2 0)
			(effects
				(font
					(size 1.27 1.27)
					(thickness 0.15)
				)
				(justify left bottom)
				(hide yes)
			)
		)
		(property "License" "Apache-2.0"
			(at 88.9 203.2 0)
			(effects
				(font
					(size 1.27 1.27)
					(thickness 0.15)
				)
				(justify left bottom)
				(hide yes)
			)
		)
		(pin "1"
		)
		(instances
			(project "k410t-devboard"
				(path ""
					(reference "TP7")
					(unit 1)
				)
			)
		)
	)
	(symbol
		(lib_id "k410t-devboard:Net-Tie_2")
		(at 242.57 255.27 90)
		(unit 1)
		(exclude_from_sim no)
		(in_bom yes)
		(on_board yes)
		(dnp no)
		(fields_autoplaced yes)
		(property "Reference" "NT27"
			(at 241.3 255.27 0)
			(effects
				(font
					(size 1.27 1.27)
				)
				(hide yes)
			)
		)
		(property "Value" "Net-Tie_2"
			(at 240.665 253.3649 90)
			(effects
				(font
					(size 1.27 1.27)
					(thickness 0.15)
				)
				(justify left)
				(hide yes)
			)
		)
		(property "Footprint" "antmicro-footprints:NetTie-2_SMD_Pad0.127mm"
			(at 247.65 233.68 0)
			(effects
				(font
					(size 1.27 1.27)
					(thickness 0.15)
				)
				(justify left bottom)
				(hide yes)
			)
		)
		(property "Datasheet" ""
			(at 250.19 233.68 0)
			(effects
				(font
					(size 1.27 1.27)
					(thickness 0.15)
				)
				(justify left bottom)
				(hide yes)
			)
		)
		(property "Description" ""
			(at 242.57 255.27 0)
			(effects
				(font
					(size 1.27 1.27)
				)
			)
		)
		(property "MPN" ""
			(at 251.46 233.68 0)
			(effects
				(font
					(size 1.27 1.27)
				)
				(justify left)
				(hide yes)
			)
		)
		(property "Manufacturer" ""
			(at 254 233.68 0)
			(effects
				(font
					(size 1.27 1.27)
				)
				(justify left)
				(hide yes)
			)
		)
		(property "Author" "Antmicro"
			(at 257.81 233.68 0)
			(effects
				(font
					(size 1.27 1.27)
					(thickness 0.15)
				)
				(justify left bottom)
				(hide yes)
			)
		)
		(property "License" "Apache-2.0"
			(at 260.35 233.68 0)
			(effects
				(font
					(size 1.27 1.27)
					(thickness 0.15)
				)
				(justify left bottom)
				(hide yes)
			)
		)
		(pin "1"
		)
		(pin "2"
		)
		(instances
			(project "k410t-devboard"
				(path ""
					(reference "NT27")
					(unit 1)
				)
			)
		)
	)
	(symbol
		(lib_id "antmicroCapacitorsmisc:C_22u_25V_0805")
		(at 49.53 100.33 90)
		(unit 1)
		(exclude_from_sim no)
		(in_bom yes)
		(on_board yes)
		(dnp no)
		(fields_autoplaced yes)
		(property "Reference" "C315"
			(at 52.07 95.2436 90)
			(effects
				(font
					(size 1.27 1.27)
				)
				(justify right)
			)
		)
		(property "Value" "C_22u_25V_0805"
			(at 53.34 100.33 0)
			(effects
				(font
					(size 1.27 1.27)
				)
				(hide yes)
			)
		)
		(property "Footprint" "antmicro-footprints:C_0805_2012Metric"
			(at 44.45 95.25 0)
			(effects
				(font
					(size 1.27 1.27)
				)
				(justify left)
				(hide yes)
			)
		)
		(property "Datasheet" "https://product.samsungsem.com/mlcc/CL21A226MAYNNN.do"
			(at 49.53 100.33 0)
			(effects
				(font
					(size 1.27 1.27)
				)
				(hide yes)
			)
		)
		(property "Description" ""
			(at 49.53 100.33 0)
			(effects
				(font
					(size 1.27 1.27)
				)
			)
		)
		(property "Manufacturer" "Samsung Electro-Mechanics"
			(at 39.37 95.25 0)
			(effects
				(font
					(size 1.27 1.27)
				)
				(justify left)
				(hide yes)
			)
		)
		(property "MPN" "CL21A226MAYNNNE"
			(at 41.91 95.25 0)
			(effects
				(font
					(size 1.27 1.27)
				)
				(justify left)
				(hide yes)
			)
		)
		(property "Val" "22u"
			(at 52.07 97.7836 90)
			(effects
				(font
					(size 1.27 1.27)
				)
				(justify right)
			)
		)
		(property "License" "Apache-2.0"
			(at 72.39 80.01 0)
			(effects
				(font
					(size 1.27 1.27)
					(thickness 0.15)
				)
				(justify left bottom)
				(hide yes)
			)
		)
		(property "Author" "Antmicro"
			(at 74.93 80.01 0)
			(effects
				(font
					(size 1.27 1.27)
					(thickness 0.15)
				)
				(justify left bottom)
				(hide yes)
			)
		)
		(property "Voltage" "25V"
			(at 52.07 100.3236 90)
			(effects
				(font
					(size 1.27 1.27)
				)
				(justify right)
			)
		)
		(property "Dielectric" "X5R"
			(at 80.01 80.01 0)
			(effects
				(font
					(size 1.27 1.27)
				)
				(justify left bottom)
				(hide yes)
			)
		)
		(pin "1"
		)
		(pin "2"
		)
		(instances
			(project "k410t-devboard"
				(path ""
					(reference "C315")
					(unit 1)
				)
			)
		)
	)
	(symbol
		(lib_id "antmicroResistors0402:R_0R_0402")
		(at 187.96 153.67 90)
		(unit 1)
		(exclude_from_sim no)
		(in_bom no)
		(on_board yes)
		(dnp yes)
		(property "Reference" "R299"
			(at 189.865 149.86 90)
			(effects
				(font
					(size 1.27 1.27)
				)
				(justify right)
			)
		)
		(property "Value" "R_0R_0402"
			(at 200.66 133.35 0)
			(effects
				(font
					(size 1.27 1.27)
					(thickness 0.15)
				)
				(justify left bottom)
				(hide yes)
			)
		)
		(property "Footprint" "antmicro-footprints:R_0402_1005Metric"
			(at 203.2 133.35 0)
			(effects
				(font
					(size 1.27 1.27)
					(thickness 0.15)
				)
				(justify left bottom)
				(hide yes)
			)
		)
		(property "Datasheet" "https://industrial.panasonic.com/cdbs/www-data/pdf/RDA0000/AOA0000C301.pdf"
			(at 205.74 133.35 0)
			(effects
				(font
					(size 1.27 1.27)
					(thickness 0.15)
				)
				(justify left bottom)
				(hide yes)
			)
		)
		(property "Description" ""
			(at 187.96 153.67 0)
			(effects
				(font
					(size 1.27 1.27)
				)
			)
		)
		(property "Manufacturer" "Panasonic"
			(at 210.82 133.35 0)
			(effects
				(font
					(size 1.27 1.27)
					(thickness 0.15)
				)
				(justify left bottom)
				(hide yes)
			)
		)
		(property "MPN" "ERJ2GE0R00X"
			(at 208.28 133.35 0)
			(effects
				(font
					(size 1.27 1.27)
					(thickness 0.15)
				)
				(justify left bottom)
				(hide yes)
			)
		)
		(property "Val" "0R"
			(at 189.865 152.4 90)
			(effects
				(font
					(size 1.27 1.27)
					(thickness 0.15)
				)
				(justify right)
			)
		)
		(property "DNP" "DNP"
			(at 187.96 149.225 0)
			(effects
				(font
					(size 1.27 1.27)
				)
				(justify right)
			)
		)
		(property "License" "Apache-2.0"
			(at 213.36 133.35 0)
			(effects
				(font
					(size 1.27 1.27)
					(thickness 0.15)
				)
				(justify left bottom)
				(hide yes)
			)
		)
		(property "Author" "Antmicro"
			(at 215.9 133.35 0)
			(effects
				(font
					(size 1.27 1.27)
					(thickness 0.15)
				)
				(justify left bottom)
				(hide yes)
			)
		)
		(property "Tolerance" "~"
			(at 198.12 133.35 0)
			(effects
				(font
					(size 1.27 1.27)
				)
				(justify left bottom)
				(hide yes)
			)
		)
		(property "Current" "1A"
			(at 189.865 154.9399 90)
			(effects
				(font
					(size 1.27 1.27)
					(thickness 0.15)
				)
				(justify right)
				(hide yes)
			)
		)
		(pin "1"
		)
		(pin "2"
		)
		(instances
			(project "k410t-devboard"
				(path ""
					(reference "R299")
					(unit 1)
				)
			)
		)
	)
	(symbol
		(lib_id "k410t-devboard:Net-Tie_2")
		(at 252.73 91.44 90)
		(unit 1)
		(exclude_from_sim no)
		(in_bom yes)
		(on_board yes)
		(dnp no)
		(fields_autoplaced yes)
		(property "Reference" "NT38"
			(at 251.46 91.44 0)
			(effects
				(font
					(size 1.27 1.27)
				)
				(hide yes)
			)
		)
		(property "Value" "Net-Tie_2"
			(at 254 89.5349 90)
			(effects
				(font
					(size 1.27 1.27)
					(thickness 0.15)
				)
				(justify right)
				(hide yes)
			)
		)
		(property "Footprint" "antmicro-footprints:NetTie-2_SMD_Pad0.127mm"
			(at 257.81 69.85 0)
			(effects
				(font
					(size 1.27 1.27)
					(thickness 0.15)
				)
				(justify left bottom)
				(hide yes)
			)
		)
		(property "Datasheet" ""
			(at 260.35 69.85 0)
			(effects
				(font
					(size 1.27 1.27)
					(thickness 0.15)
				)
				(justify left bottom)
				(hide yes)
			)
		)
		(property "Description" ""
			(at 252.73 91.44 0)
			(effects
				(font
					(size 1.27 1.27)
				)
			)
		)
		(property "MPN" ""
			(at 261.62 69.85 0)
			(effects
				(font
					(size 1.27 1.27)
				)
				(justify left)
				(hide yes)
			)
		)
		(property "Manufacturer" ""
			(at 264.16 69.85 0)
			(effects
				(font
					(size 1.27 1.27)
				)
				(justify left)
				(hide yes)
			)
		)
		(property "Author" "Antmicro"
			(at 267.97 69.85 0)
			(effects
				(font
					(size 1.27 1.27)
					(thickness 0.15)
				)
				(justify left bottom)
				(hide yes)
			)
		)
		(property "License" "Apache-2.0"
			(at 270.51 69.85 0)
			(effects
				(font
					(size 1.27 1.27)
					(thickness 0.15)
				)
				(justify left bottom)
				(hide yes)
			)
		)
		(pin "1"
		)
		(pin "2"
		)
		(instances
			(project "k410t-devboard"
				(path ""
					(reference "NT38")
					(unit 1)
				)
			)
		)
	)
	(symbol
		(lib_id "antmicroCapacitors0402:C_10u_0402")
		(at 290.83 228.6 90)
		(unit 1)
		(exclude_from_sim no)
		(in_bom yes)
		(on_board yes)
		(dnp no)
		(property "Reference" "C344"
			(at 291.465 224.155 90)
			(effects
				(font
					(size 1.27 1.27)
				)
				(justify right)
			)
		)
		(property "Value" "C_10u_0402"
			(at 300.99 208.28 0)
			(effects
				(font
					(size 1.27 1.27)
					(thickness 0.15)
				)
				(justify left bottom)
				(hide yes)
			)
		)
		(property "Footprint" "antmicro-footprints:C_0402_1005Metric"
			(at 303.53 208.28 0)
			(effects
				(font
					(size 1.27 1.27)
					(thickness 0.15)
				)
				(justify left bottom)
				(hide yes)
			)
		)
		(property "Datasheet" "https://www.yageo.com/en/Chart/Download/pdf/CC0402MRX5R5BB106"
			(at 306.07 208.28 0)
			(effects
				(font
					(size 1.27 1.27)
					(thickness 0.15)
				)
				(justify left bottom)
				(hide yes)
			)
		)
		(property "Description" ""
			(at 290.83 228.6 0)
			(effects
				(font
					(size 1.27 1.27)
				)
			)
		)
		(property "Manufacturer" "YAGEO"
			(at 311.15 208.28 0)
			(effects
				(font
					(size 1.27 1.27)
					(thickness 0.15)
				)
				(justify left bottom)
				(hide yes)
			)
		)
		(property "MPN" "CC0402MRX5R5BB106"
			(at 308.61 208.28 0)
			(effects
				(font
					(size 1.27 1.27)
					(thickness 0.15)
				)
				(justify left bottom)
				(hide yes)
			)
		)
		(property "Val" "10u"
			(at 291.465 227.965 90)
			(effects
				(font
					(size 1.27 1.27)
					(thickness 0.15)
				)
				(justify right)
			)
		)
		(property "License" "Apache-2.0"
			(at 313.69 208.28 0)
			(effects
				(font
					(size 1.27 1.27)
					(thickness 0.15)
				)
				(justify left bottom)
				(hide yes)
			)
		)
		(property "Author" "Antmicro"
			(at 316.23 208.28 0)
			(effects
				(font
					(size 1.27 1.27)
					(thickness 0.15)
				)
				(justify left bottom)
				(hide yes)
			)
		)
		(property "Voltage" ""
			(at 318.77 208.28 0)
			(effects
				(font
					(size 1.27 1.27)
				)
				(justify left bottom)
				(hide yes)
			)
		)
		(property "Dielectric" ""
			(at 321.31 208.28 0)
			(effects
				(font
					(size 1.27 1.27)
				)
				(justify left bottom)
				(hide yes)
			)
		)
		(pin "1"
		)
		(pin "2"
		)
		(instances
			(project "k410t-devboard"
				(path ""
					(reference "C344")
					(unit 1)
				)
			)
		)
	)
	(symbol
		(lib_id "antmicropower:GND")
		(at 49.53 104.14 0)
		(unit 1)
		(exclude_from_sim no)
		(in_bom yes)
		(on_board yes)
		(dnp no)
		(property "Reference" "#PWR0360"
			(at 49.53 110.49 0)
			(effects
				(font
					(size 1.27 1.27)
				)
				(hide yes)
			)
		)
		(property "Value" "GND"
			(at 49.53 107.95 0)
			(effects
				(font
					(size 1.27 1.27)
				)
			)
		)
		(property "Footprint" ""
			(at 58.42 111.76 0)
			(effects
				(font
					(size 1.27 1.27)
					(thickness 0.15)
				)
				(justify left bottom)
				(hide yes)
			)
		)
		(property "Datasheet" ""
			(at 58.42 116.84 0)
			(effects
				(font
					(size 1.27 1.27)
					(thickness 0.15)
				)
				(justify left bottom)
				(hide yes)
			)
		)
		(property "Description" ""
			(at 49.53 104.14 0)
			(effects
				(font
					(size 1.27 1.27)
				)
			)
		)
		(property "Author" "Antmicro"
			(at 58.42 111.76 0)
			(effects
				(font
					(size 1.27 1.27)
					(thickness 0.15)
				)
				(justify left bottom)
				(hide yes)
			)
		)
		(property "License" "Apache-2.0"
			(at 58.42 114.3 0)
			(effects
				(font
					(size 1.27 1.27)
					(thickness 0.15)
				)
				(justify left bottom)
				(hide yes)
			)
		)
		(pin "1"
		)
		(instances
			(project "k410t-devboard"
				(path ""
					(reference "#PWR0360")
					(unit 1)
				)
			)
		)
	)
	(symbol
		(lib_id "antmicroCapacitors0402:C_1u_0402")
		(at 49.53 120.65 90)
		(unit 1)
		(exclude_from_sim no)
		(in_bom yes)
		(on_board yes)
		(dnp no)
		(fields_autoplaced yes)
		(property "Reference" "C316"
			(at 52.07 116.8335 90)
			(effects
				(font
					(size 1.27 1.27)
				)
				(justify right)
			)
		)
		(property "Value" "C_1u_0402"
			(at 53.34 120.65 0)
			(effects
				(font
					(size 1.27 1.27)
				)
				(hide yes)
			)
		)
		(property "Footprint" "antmicro-footprints:C_0402_1005Metric"
			(at 44.45 115.57 0)
			(effects
				(font
					(size 1.27 1.27)
				)
				(justify left)
				(hide yes)
			)
		)
		(property "Datasheet" "https://product.tdk.com/en/search/capacitor/ceramic/mlcc/info?part_no=C1005X6S1A105K050BC"
			(at 49.53 120.65 0)
			(effects
				(font
					(size 1.27 1.27)
				)
				(hide yes)
			)
		)
		(property "Description" ""
			(at 49.53 120.65 0)
			(effects
				(font
					(size 1.27 1.27)
				)
			)
		)
		(property "Manufacturer" "TDK"
			(at 39.37 115.57 0)
			(effects
				(font
					(size 1.27 1.27)
				)
				(justify left)
				(hide yes)
			)
		)
		(property "MPN" "C1005X6S1A105K050BC"
			(at 41.91 115.57 0)
			(effects
				(font
					(size 1.27 1.27)
				)
				(justify left)
				(hide yes)
			)
		)
		(property "Val" "1u"
			(at 52.07 119.3735 90)
			(effects
				(font
					(size 1.27 1.27)
				)
				(justify right)
			)
		)
		(property "License" "Apache-2.0"
			(at 72.39 100.33 0)
			(effects
				(font
					(size 1.27 1.27)
					(thickness 0.15)
				)
				(justify left bottom)
				(hide yes)
			)
		)
		(property "Author" "Antmicro"
			(at 74.93 100.33 0)
			(effects
				(font
					(size 1.27 1.27)
					(thickness 0.15)
				)
				(justify left bottom)
				(hide yes)
			)
		)
		(property "Voltage" ""
			(at 77.47 100.33 0)
			(effects
				(font
					(size 1.27 1.27)
				)
				(justify left bottom)
				(hide yes)
			)
		)
		(property "Dielectric" ""
			(at 80.01 100.33 0)
			(effects
				(font
					(size 1.27 1.27)
				)
				(justify left bottom)
				(hide yes)
			)
		)
		(pin "1"
		)
		(pin "2"
		)
		(instances
			(project "k410t-devboard"
				(path ""
					(reference "C316")
					(unit 1)
				)
			)
		)
	)
	(symbol
		(lib_id "k410t-devboard:Net-Tie_2")
		(at 189.23 217.17 90)
		(unit 1)
		(exclude_from_sim no)
		(in_bom yes)
		(on_board yes)
		(dnp no)
		(fields_autoplaced yes)
		(property "Reference" "NT29"
			(at 187.96 217.17 0)
			(effects
				(font
					(size 1.27 1.27)
				)
				(hide yes)
			)
		)
		(property "Value" "Net-Tie_2"
			(at 187.96 215.2649 90)
			(effects
				(font
					(size 1.27 1.27)
					(thickness 0.15)
				)
				(justify left)
				(hide yes)
			)
		)
		(property "Footprint" "antmicro-footprints:NetTie-2_SMD_Pad0.127mm"
			(at 194.31 195.58 0)
			(effects
				(font
					(size 1.27 1.27)
					(thickness 0.15)
				)
				(justify left bottom)
				(hide yes)
			)
		)
		(property "Datasheet" ""
			(at 196.85 195.58 0)
			(effects
				(font
					(size 1.27 1.27)
					(thickness 0.15)
				)
				(justify left bottom)
				(hide yes)
			)
		)
		(property "Description" ""
			(at 189.23 217.17 0)
			(effects
				(font
					(size 1.27 1.27)
				)
			)
		)
		(property "MPN" ""
			(at 198.12 195.58 0)
			(effects
				(font
					(size 1.27 1.27)
				)
				(justify left)
				(hide yes)
			)
		)
		(property "Manufacturer" ""
			(at 200.66 195.58 0)
			(effects
				(font
					(size 1.27 1.27)
				)
				(justify left)
				(hide yes)
			)
		)
		(property "Author" "Antmicro"
			(at 204.47 195.58 0)
			(effects
				(font
					(size 1.27 1.27)
					(thickness 0.15)
				)
				(justify left bottom)
				(hide yes)
			)
		)
		(property "License" "Apache-2.0"
			(at 207.01 195.58 0)
			(effects
				(font
					(size 1.27 1.27)
					(thickness 0.15)
				)
				(justify left bottom)
				(hide yes)
			)
		)
		(pin "1"
		)
		(pin "2"
		)
		(instances
			(project "k410t-devboard"
				(path ""
					(reference "NT29")
					(unit 1)
				)
			)
		)
	)
	(symbol
		(lib_id "antmicropower:GND")
		(at 401.32 217.17 0)
		(mirror y)
		(unit 1)
		(exclude_from_sim no)
		(in_bom yes)
		(on_board yes)
		(dnp no)
		(property "Reference" "#PWR0457"
			(at 401.32 223.52 0)
			(effects
				(font
					(size 1.27 1.27)
				)
				(hide yes)
			)
		)
		(property "Value" "GND"
			(at 401.32 220.98 0)
			(effects
				(font
					(size 1.27 1.27)
				)
			)
		)
		(property "Footprint" ""
			(at 392.43 224.79 0)
			(effects
				(font
					(size 1.27 1.27)
					(thickness 0.15)
				)
				(justify left bottom)
				(hide yes)
			)
		)
		(property "Datasheet" ""
			(at 392.43 229.87 0)
			(effects
				(font
					(size 1.27 1.27)
					(thickness 0.15)
				)
				(justify left bottom)
				(hide yes)
			)
		)
		(property "Description" ""
			(at 401.32 217.17 0)
			(effects
				(font
					(size 1.27 1.27)
				)
			)
		)
		(property "Author" "Antmicro"
			(at 392.43 224.79 0)
			(effects
				(font
					(size 1.27 1.27)
					(thickness 0.15)
				)
				(justify left bottom)
				(hide yes)
			)
		)
		(property "License" "Apache-2.0"
			(at 392.43 227.33 0)
			(effects
				(font
					(size 1.27 1.27)
					(thickness 0.15)
				)
				(justify left bottom)
				(hide yes)
			)
		)
		(pin "1"
		)
		(instances
			(project "k410t-devboard"
				(path ""
					(reference "#PWR0457")
					(unit 1)
				)
			)
		)
	)
	(symbol
		(lib_id "antmicropower:PWR_FLAG")
		(at 118.11 182.88 0)
		(unit 1)
		(exclude_from_sim no)
		(in_bom yes)
		(on_board yes)
		(dnp no)
		(fields_autoplaced yes)
		(property "Reference" "#FLG0101"
			(at 118.11 180.975 0)
			(effects
				(font
					(size 1.27 1.27)
				)
				(hide yes)
			)
		)
		(property "Value" "PWR_FLAG"
			(at 118.11 179.07 0)
			(effects
				(font
					(size 1.27 1.27)
				)
			)
		)
		(property "Footprint" ""
			(at 118.11 182.88 0)
			(effects
				(font
					(size 1.27 1.27)
				)
				(hide yes)
			)
		)
		(property "Datasheet" ""
			(at 118.11 182.88 0)
			(effects
				(font
					(size 1.27 1.27)
				)
				(hide yes)
			)
		)
		(property "Description" ""
			(at 118.11 182.88 0)
			(effects
				(font
					(size 1.27 1.27)
				)
			)
		)
		(pin "1"
		)
		(instances
			(project "k410t-devboard"
				(path ""
					(reference "#FLG0101")
					(unit 1)
				)
			)
		)
	)
	(symbol
		(lib_id "antmicroResistors0402:R_47k_0402")
		(at 245.11 44.45 90)
		(unit 1)
		(exclude_from_sim no)
		(in_bom yes)
		(on_board yes)
		(dnp no)
		(property "Reference" "R318"
			(at 246.38 40.64 90)
			(effects
				(font
					(size 1.27 1.27)
				)
				(justify right)
			)
		)
		(property "Value" "R_47k_0402"
			(at 257.81 24.13 0)
			(effects
				(font
					(size 1.27 1.27)
					(thickness 0.15)
				)
				(justify left bottom)
				(hide yes)
			)
		)
		(property "Footprint" "antmicro-footprints:R_0402_1005Metric"
			(at 260.35 24.13 0)
			(effects
				(font
					(size 1.27 1.27)
					(thickness 0.15)
				)
				(justify left bottom)
				(hide yes)
			)
		)
		(property "Datasheet" "https://www.bourns.com/docs/product-datasheets/cr.pdf"
			(at 262.89 24.13 0)
			(effects
				(font
					(size 1.27 1.27)
					(thickness 0.15)
				)
				(justify left bottom)
				(hide yes)
			)
		)
		(property "Description" ""
			(at 245.11 44.45 0)
			(effects
				(font
					(size 1.27 1.27)
				)
			)
		)
		(property "Manufacturer" "Bourns"
			(at 267.97 24.13 0)
			(effects
				(font
					(size 1.27 1.27)
					(thickness 0.15)
				)
				(justify left bottom)
				(hide yes)
			)
		)
		(property "MPN" "CR0402-FX-4702GLF"
			(at 265.43 24.13 0)
			(effects
				(font
					(size 1.27 1.27)
					(thickness 0.15)
				)
				(justify left bottom)
				(hide yes)
			)
		)
		(property "Val" "47k"
			(at 246.38 43.18 90)
			(effects
				(font
					(size 1.27 1.27)
					(thickness 0.15)
				)
				(justify right)
			)
		)
		(property "License" "Apache-2.0"
			(at 270.51 24.13 0)
			(effects
				(font
					(size 1.27 1.27)
					(thickness 0.15)
				)
				(justify left bottom)
				(hide yes)
			)
		)
		(property "Author" "Antmicro"
			(at 273.05 24.13 0)
			(effects
				(font
					(size 1.27 1.27)
					(thickness 0.15)
				)
				(justify left bottom)
				(hide yes)
			)
		)
		(property "Tolerance" "1%"
			(at 255.27 24.13 0)
			(effects
				(font
					(size 1.27 1.27)
				)
				(justify left bottom)
				(hide yes)
			)
		)
		(pin "1"
		)
		(pin "2"
		)
		(instances
			(project "k410t-devboard"
				(path ""
					(reference "R318")
					(unit 1)
				)
			)
		)
	)
	(symbol
		(lib_id "antmicropower:GND")
		(at 323.85 179.07 0)
		(unit 1)
		(exclude_from_sim no)
		(in_bom yes)
		(on_board yes)
		(dnp no)
		(fields_autoplaced yes)
		(property "Reference" "#PWR0421"
			(at 323.85 185.42 0)
			(effects
				(font
					(size 1.27 1.27)
				)
				(hide yes)
			)
		)
		(property "Value" "GND"
			(at 323.85 182.88 0)
			(effects
				(font
					(size 1.27 1.27)
				)
			)
		)
		(property "Footprint" ""
			(at 332.74 186.69 0)
			(effects
				(font
					(size 1.27 1.27)
					(thickness 0.15)
				)
				(justify left bottom)
				(hide yes)
			)
		)
		(property "Datasheet" ""
			(at 332.74 191.77 0)
			(effects
				(font
					(size 1.27 1.27)
					(thickness 0.15)
				)
				(justify left bottom)
				(hide yes)
			)
		)
		(property "Description" ""
			(at 323.85 179.07 0)
			(effects
				(font
					(size 1.27 1.27)
				)
			)
		)
		(property "Author" "Antmicro"
			(at 332.74 186.69 0)
			(effects
				(font
					(size 1.27 1.27)
					(thickness 0.15)
				)
				(justify left bottom)
				(hide yes)
			)
		)
		(property "License" "Apache-2.0"
			(at 332.74 189.23 0)
			(effects
				(font
					(size 1.27 1.27)
					(thickness 0.15)
				)
				(justify left bottom)
				(hide yes)
			)
		)
		(pin "1"
		)
		(instances
			(project "k410t-devboard"
				(path ""
					(reference "#PWR0421")
					(unit 1)
				)
			)
		)
	)
	(symbol
		(lib_id "antmicroPMICVoltageRegulatorsDCDCSwitchingRegulators:MPM54304GMN")
		(at 71.12 199.39 0)
		(unit 1)
		(exclude_from_sim no)
		(in_bom yes)
		(on_board yes)
		(dnp no)
		(property "Reference" "U32"
			(at 85.09 192.405 0)
			(effects
				(font
					(size 1.27 1.27)
				)
			)
		)
		(property "Value" "MPM54304GMN"
			(at 85.09 194.945 0)
			(effects
				(font
					(size 1.27 1.27)
				)
			)
		)
		(property "Footprint" "antmicro-footprints:LGA-33_7x7mm_P0.65mm"
			(at 93.98 227.33 0)
			(effects
				(font
					(size 1.27 1.27)
				)
				(hide yes)
			)
		)
		(property "Datasheet" "https://www.monolithicpower.com/en/documentview/productdocument/index/version/2/document_type/Datasheet/lang/en/sku/MPM54304/document_id/4982/"
			(at 167.64 229.87 0)
			(effects
				(font
					(size 1.27 1.27)
				)
				(hide yes)
			)
		)
		(property "Description" ""
			(at 71.12 199.39 0)
			(effects
				(font
					(size 1.27 1.27)
				)
			)
		)
		(property "MPN" "MPM54304GMN-0000"
			(at 81.28 224.79 0)
			(effects
				(font
					(size 1.27 1.27)
				)
				(hide yes)
			)
		)
		(property "Manufacturer" "Monolithic Power Systems"
			(at 80.01 222.25 0)
			(effects
				(font
					(size 1.27 1.27)
				)
				(hide yes)
			)
		)
		(property "Author" "Antmicro"
			(at 118.11 217.17 0)
			(effects
				(font
					(size 1.27 1.27)
					(thickness 0.15)
				)
				(justify left bottom)
				(hide yes)
			)
		)
		(property "License" "Apache-2.0"
			(at 118.11 219.71 0)
			(effects
				(font
					(size 1.27 1.27)
					(thickness 0.15)
				)
				(justify left bottom)
				(hide yes)
			)
		)
		(pin "1"
		)
		(pin "10"
		)
		(pin "11"
		)
		(pin "12"
		)
		(pin "13"
		)
		(pin "14"
		)
		(pin "15"
		)
		(pin "16"
		)
		(pin "17"
		)
		(pin "18"
		)
		(pin "19"
		)
		(pin "2"
		)
		(pin "20"
		)
		(pin "21"
		)
		(pin "22"
		)
		(pin "23"
		)
		(pin "24"
		)
		(pin "25"
		)
		(pin "26"
		)
		(pin "27"
		)
		(pin "28"
		)
		(pin "29"
		)
		(pin "3"
		)
		(pin "30"
		)
		(pin "31"
		)
		(pin "32"
		)
		(pin "33"
		)
		(pin "4"
		)
		(pin "5"
		)
		(pin "6"
		)
		(pin "7"
		)
		(pin "8"
		)
		(pin "9"
		)
		(instances
			(project "k410t-devboard"
				(path ""
					(reference "U32")
					(unit 1)
				)
			)
		)
	)
	(symbol
		(lib_id "antmicropower:GND")
		(at 403.86 242.57 0)
		(mirror y)
		(unit 1)
		(exclude_from_sim no)
		(in_bom yes)
		(on_board yes)
		(dnp no)
		(property "Reference" "#PWR0458"
			(at 403.86 248.92 0)
			(effects
				(font
					(size 1.27 1.27)
				)
				(hide yes)
			)
		)
		(property "Value" "GND"
			(at 403.86 246.38 0)
			(effects
				(font
					(size 1.27 1.27)
				)
			)
		)
		(property "Footprint" ""
			(at 394.97 250.19 0)
			(effects
				(font
					(size 1.27 1.27)
					(thickness 0.15)
				)
				(justify left bottom)
				(hide yes)
			)
		)
		(property "Datasheet" ""
			(at 394.97 255.27 0)
			(effects
				(font
					(size 1.27 1.27)
					(thickness 0.15)
				)
				(justify left bottom)
				(hide yes)
			)
		)
		(property "Description" ""
			(at 403.86 242.57 0)
			(effects
				(font
					(size 1.27 1.27)
				)
			)
		)
		(property "Author" "Antmicro"
			(at 394.97 250.19 0)
			(effects
				(font
					(size 1.27 1.27)
					(thickness 0.15)
				)
				(justify left bottom)
				(hide yes)
			)
		)
		(property "License" "Apache-2.0"
			(at 394.97 252.73 0)
			(effects
				(font
					(size 1.27 1.27)
					(thickness 0.15)
				)
				(justify left bottom)
				(hide yes)
			)
		)
		(pin "1"
		)
		(instances
			(project "k410t-devboard"
				(path ""
					(reference "#PWR0458")
					(unit 1)
				)
			)
		)
	)
	(symbol
		(lib_id "antmicroLogicTranslatorsLevelShifters:74LVC1T45GM")
		(at 386.08 233.68 0)
		(unit 1)
		(exclude_from_sim no)
		(in_bom yes)
		(on_board yes)
		(dnp no)
		(property "Reference" "U47"
			(at 394.335 228.6 0)
			(effects
				(font
					(size 1.27 1.27)
				)
			)
		)
		(property "Value" "74LVC1T45GM"
			(at 394.335 231.14 0)
			(effects
				(font
					(size 1.27 1.27)
					(thickness 0.15)
				)
			)
		)
		(property "Footprint" "antmicro-footprints:SOT-886"
			(at 416.56 243.84 0)
			(effects
				(font
					(size 1.27 1.27)
					(thickness 0.15)
				)
				(justify left bottom)
				(hide yes)
			)
		)
		(property "Datasheet" "http://www.ti.com/general/docs/suppproductinfo.tsp?distId=10&gotoUrl=http%3A%2F%2Fwww.ti.com%2Flit%2Fgpn%2Fsn74lvc1t45"
			(at 416.56 246.38 0)
			(effects
				(font
					(size 1.27 1.27)
					(thickness 0.15)
				)
				(justify left bottom)
				(hide yes)
			)
		)
		(property "Description" ""
			(at 386.08 233.68 0)
			(effects
				(font
					(size 1.27 1.27)
				)
			)
		)
		(property "MPN" "74LVC1T45GM-Q100X"
			(at 416.56 248.92 0)
			(effects
				(font
					(size 1.27 1.27)
					(thickness 0.15)
				)
				(justify left bottom)
				(hide yes)
			)
		)
		(property "Manufacturer" "Nexperia"
			(at 416.56 251.46 0)
			(effects
				(font
					(size 1.27 1.27)
					(thickness 0.15)
				)
				(justify left bottom)
				(hide yes)
			)
		)
		(property "Author" "Antmicro"
			(at 416.56 254 0)
			(effects
				(font
					(size 1.27 1.27)
					(thickness 0.15)
				)
				(justify left bottom)
				(hide yes)
			)
		)
		(property "License" "Apache-2.0"
			(at 416.56 256.54 0)
			(effects
				(font
					(size 1.27 1.27)
					(thickness 0.15)
				)
				(justify left bottom)
				(hide yes)
			)
		)
		(pin "1"
		)
		(pin "2"
		)
		(pin "3"
		)
		(pin "4"
		)
		(pin "5"
		)
		(pin "6"
		)
		(instances
			(project "k410t-devboard"
				(path ""
					(reference "U47")
					(unit 1)
				)
			)
		)
	)
	(symbol
		(lib_id "antmicroResistors0402:R_0R_0402")
		(at 245.11 151.13 90)
		(unit 1)
		(exclude_from_sim no)
		(in_bom no)
		(on_board yes)
		(dnp yes)
		(property "Reference" "R312"
			(at 247.015 147.32 90)
			(effects
				(font
					(size 1.27 1.27)
				)
				(justify right)
			)
		)
		(property "Value" "R_0R_0402"
			(at 257.81 130.81 0)
			(effects
				(font
					(size 1.27 1.27)
					(thickness 0.15)
				)
				(justify left bottom)
				(hide yes)
			)
		)
		(property "Footprint" "antmicro-footprints:R_0402_1005Metric"
			(at 260.35 130.81 0)
			(effects
				(font
					(size 1.27 1.27)
					(thickness 0.15)
				)
				(justify left bottom)
				(hide yes)
			)
		)
		(property "Datasheet" "https://industrial.panasonic.com/cdbs/www-data/pdf/RDA0000/AOA0000C301.pdf"
			(at 262.89 130.81 0)
			(effects
				(font
					(size 1.27 1.27)
					(thickness 0.15)
				)
				(justify left bottom)
				(hide yes)
			)
		)
		(property "Description" ""
			(at 245.11 151.13 0)
			(effects
				(font
					(size 1.27 1.27)
				)
			)
		)
		(property "Manufacturer" "Panasonic"
			(at 267.97 130.81 0)
			(effects
				(font
					(size 1.27 1.27)
					(thickness 0.15)
				)
				(justify left bottom)
				(hide yes)
			)
		)
		(property "MPN" "ERJ2GE0R00X"
			(at 265.43 130.81 0)
			(effects
				(font
					(size 1.27 1.27)
					(thickness 0.15)
				)
				(justify left bottom)
				(hide yes)
			)
		)
		(property "Val" "0R"
			(at 247.015 149.86 90)
			(effects
				(font
					(size 1.27 1.27)
					(thickness 0.15)
				)
				(justify right)
			)
		)
		(property "DNP" "DNP"
			(at 245.11 146.685 0)
			(effects
				(font
					(size 1.27 1.27)
				)
				(justify right)
			)
		)
		(property "License" "Apache-2.0"
			(at 270.51 130.81 0)
			(effects
				(font
					(size 1.27 1.27)
					(thickness 0.15)
				)
				(justify left bottom)
				(hide yes)
			)
		)
		(property "Author" "Antmicro"
			(at 273.05 130.81 0)
			(effects
				(font
					(size 1.27 1.27)
					(thickness 0.15)
				)
				(justify left bottom)
				(hide yes)
			)
		)
		(property "Tolerance" "~"
			(at 255.27 130.81 0)
			(effects
				(font
					(size 1.27 1.27)
				)
				(justify left bottom)
				(hide yes)
			)
		)
		(property "Current" "1A"
			(at 247.015 152.3999 90)
			(effects
				(font
					(size 1.27 1.27)
					(thickness 0.15)
				)
				(justify right)
				(hide yes)
			)
		)
		(pin "1"
		)
		(pin "2"
		)
		(instances
			(project "k410t-devboard"
				(path ""
					(reference "R312")
					(unit 1)
				)
			)
		)
	)
	(symbol
		(lib_id "antmicroResistors0402:R_10k_0402")
		(at 356.87 60.96 0)
		(unit 1)
		(exclude_from_sim no)
		(in_bom yes)
		(on_board yes)
		(dnp no)
		(property "Reference" "R327"
			(at 359.41 58.42 0)
			(effects
				(font
					(size 1.27 1.27)
				)
			)
		)
		(property "Value" "R_10k_0402"
			(at 377.19 73.66 0)
			(effects
				(font
					(size 1.27 1.27)
					(thickness 0.15)
				)
				(justify left bottom)
				(hide yes)
			)
		)
		(property "Footprint" "antmicro-footprints:R_0402_1005Metric"
			(at 377.19 76.2 0)
			(effects
				(font
					(size 1.27 1.27)
					(thickness 0.15)
				)
				(justify left bottom)
				(hide yes)
			)
		)
		(property "Datasheet" "https://www.bourns.com/docs/product-datasheets/cr.pdf"
			(at 377.19 78.74 0)
			(effects
				(font
					(size 1.27 1.27)
					(thickness 0.15)
				)
				(justify left bottom)
				(hide yes)
			)
		)
		(property "Description" ""
			(at 356.87 60.96 0)
			(effects
				(font
					(size 1.27 1.27)
				)
			)
		)
		(property "Manufacturer" "Bourns"
			(at 377.19 83.82 0)
			(effects
				(font
					(size 1.27 1.27)
					(thickness 0.15)
				)
				(justify left bottom)
				(hide yes)
			)
		)
		(property "MPN" "CR0402-FX-1002GLF"
			(at 377.19 81.28 0)
			(effects
				(font
					(size 1.27 1.27)
					(thickness 0.15)
				)
				(justify left bottom)
				(hide yes)
			)
		)
		(property "Val" "10k"
			(at 359.41 63.5 0)
			(effects
				(font
					(size 1.27 1.27)
					(thickness 0.15)
				)
			)
		)
		(property "License" "Apache-2.0"
			(at 377.19 86.36 0)
			(effects
				(font
					(size 1.27 1.27)
					(thickness 0.15)
				)
				(justify left bottom)
				(hide yes)
			)
		)
		(property "Author" "Antmicro"
			(at 377.19 88.9 0)
			(effects
				(font
					(size 1.27 1.27)
					(thickness 0.15)
				)
				(justify left bottom)
				(hide yes)
			)
		)
		(property "Tolerance" "1%"
			(at 377.19 71.12 0)
			(effects
				(font
					(size 1.27 1.27)
				)
				(justify left bottom)
				(hide yes)
			)
		)
		(pin "1"
		)
		(pin "2"
		)
		(instances
			(project "k410t-devboard"
				(path ""
					(reference "R327")
					(unit 1)
				)
			)
		)
	)
	(symbol
		(lib_id "antmicroResistors0402:R_0R_0402")
		(at 201.93 143.51 90)
		(unit 1)
		(exclude_from_sim no)
		(in_bom no)
		(on_board yes)
		(dnp yes)
		(property "Reference" "R305"
			(at 203.835 139.7 90)
			(effects
				(font
					(size 1.27 1.27)
				)
				(justify right)
			)
		)
		(property "Value" "R_0R_0402"
			(at 214.63 123.19 0)
			(effects
				(font
					(size 1.27 1.27)
					(thickness 0.15)
				)
				(justify left bottom)
				(hide yes)
			)
		)
		(property "Footprint" "antmicro-footprints:R_0402_1005Metric"
			(at 217.17 123.19 0)
			(effects
				(font
					(size 1.27 1.27)
					(thickness 0.15)
				)
				(justify left bottom)
				(hide yes)
			)
		)
		(property "Datasheet" "https://industrial.panasonic.com/cdbs/www-data/pdf/RDA0000/AOA0000C301.pdf"
			(at 219.71 123.19 0)
			(effects
				(font
					(size 1.27 1.27)
					(thickness 0.15)
				)
				(justify left bottom)
				(hide yes)
			)
		)
		(property "Description" ""
			(at 201.93 143.51 0)
			(effects
				(font
					(size 1.27 1.27)
				)
			)
		)
		(property "Manufacturer" "Panasonic"
			(at 224.79 123.19 0)
			(effects
				(font
					(size 1.27 1.27)
					(thickness 0.15)
				)
				(justify left bottom)
				(hide yes)
			)
		)
		(property "MPN" "ERJ2GE0R00X"
			(at 222.25 123.19 0)
			(effects
				(font
					(size 1.27 1.27)
					(thickness 0.15)
				)
				(justify left bottom)
				(hide yes)
			)
		)
		(property "Val" "0R"
			(at 203.835 142.24 90)
			(effects
				(font
					(size 1.27 1.27)
					(thickness 0.15)
				)
				(justify right)
			)
		)
		(property "DNP" "DNP"
			(at 201.93 139.065 0)
			(effects
				(font
					(size 1.27 1.27)
				)
				(justify right)
			)
		)
		(property "License" "Apache-2.0"
			(at 227.33 123.19 0)
			(effects
				(font
					(size 1.27 1.27)
					(thickness 0.15)
				)
				(justify left bottom)
				(hide yes)
			)
		)
		(property "Author" "Antmicro"
			(at 229.87 123.19 0)
			(effects
				(font
					(size 1.27 1.27)
					(thickness 0.15)
				)
				(justify left bottom)
				(hide yes)
			)
		)
		(property "Tolerance" "~"
			(at 212.09 123.19 0)
			(effects
				(font
					(size 1.27 1.27)
				)
				(justify left bottom)
				(hide yes)
			)
		)
		(property "Current" "1A"
			(at 203.835 144.7799 90)
			(effects
				(font
					(size 1.27 1.27)
					(thickness 0.15)
				)
				(justify right)
				(hide yes)
			)
		)
		(pin "1"
		)
		(pin "2"
		)
		(instances
			(project "k410t-devboard"
				(path ""
					(reference "R305")
					(unit 1)
				)
			)
		)
	)
	(symbol
		(lib_id "antmicroCapacitors0402:C_100n_0402")
		(at 213.36 58.42 90)
		(unit 1)
		(exclude_from_sim no)
		(in_bom no)
		(on_board yes)
		(dnp yes)
		(property "Reference" "C339"
			(at 213.995 53.975 90)
			(effects
				(font
					(size 1.27 1.27)
				)
				(justify right)
			)
		)
		(property "Value" "C_100n_0402"
			(at 223.52 38.1 0)
			(effects
				(font
					(size 1.27 1.27)
					(thickness 0.15)
				)
				(justify left bottom)
				(hide yes)
			)
		)
		(property "Footprint" "antmicro-footprints:C_0402_1005Metric"
			(at 226.06 38.1 0)
			(effects
				(font
					(size 1.27 1.27)
					(thickness 0.15)
				)
				(justify left bottom)
				(hide yes)
			)
		)
		(property "Datasheet" "https://www.murata.com/products/productdetail?partno=GRM155R61H104KE14%23"
			(at 228.6 38.1 0)
			(effects
				(font
					(size 1.27 1.27)
					(thickness 0.15)
				)
				(justify left bottom)
				(hide yes)
			)
		)
		(property "Description" ""
			(at 213.36 58.42 0)
			(effects
				(font
					(size 1.27 1.27)
				)
			)
		)
		(property "Manufacturer" "Murata"
			(at 233.68 38.1 0)
			(effects
				(font
					(size 1.27 1.27)
					(thickness 0.15)
				)
				(justify left bottom)
				(hide yes)
			)
		)
		(property "MPN" "GRM155R61H104KE14D"
			(at 231.14 38.1 0)
			(effects
				(font
					(size 1.27 1.27)
					(thickness 0.15)
				)
				(justify left bottom)
				(hide yes)
			)
		)
		(property "Val" "100n"
			(at 213.995 57.785 90)
			(effects
				(font
					(size 1.27 1.27)
					(thickness 0.15)
				)
				(justify right)
			)
		)
		(property "DNP" "DNP"
			(at 215.265 55.88 90)
			(effects
				(font
					(size 1.27 1.27)
				)
				(justify right)
			)
		)
		(property "License" "Apache-2.0"
			(at 236.22 38.1 0)
			(effects
				(font
					(size 1.27 1.27)
					(thickness 0.15)
				)
				(justify left bottom)
				(hide yes)
			)
		)
		(property "Author" "Antmicro"
			(at 238.76 38.1 0)
			(effects
				(font
					(size 1.27 1.27)
					(thickness 0.15)
				)
				(justify left bottom)
				(hide yes)
			)
		)
		(property "Voltage" "50V"
			(at 241.3 38.1 0)
			(effects
				(font
					(size 1.27 1.27)
				)
				(justify left bottom)
				(hide yes)
			)
		)
		(property "Dielectric" "X5R"
			(at 243.84 38.1 0)
			(effects
				(font
					(size 1.27 1.27)
				)
				(justify left bottom)
				(hide yes)
			)
		)
		(pin "1"
		)
		(pin "2"
		)
		(instances
			(project "k410t-devboard"
				(path ""
					(reference "C339")
					(unit 1)
				)
			)
		)
	)
	(symbol
		(lib_id "antmicroCapacitors0603:C_22u_0603")
		(at 119.38 160.02 90)
		(unit 1)
		(exclude_from_sim no)
		(in_bom yes)
		(on_board yes)
		(dnp no)
		(property "Reference" "C329"
			(at 120.015 155.575 90)
			(effects
				(font
					(size 1.27 1.27)
				)
				(justify right)
			)
		)
		(property "Value" "C_22u_0603"
			(at 129.54 139.7 0)
			(effects
				(font
					(size 1.27 1.27)
					(thickness 0.15)
				)
				(justify left bottom)
				(hide yes)
			)
		)
		(property "Footprint" "antmicro-footprints:C_0603_1608Metric"
			(at 132.08 139.7 0)
			(effects
				(font
					(size 1.27 1.27)
					(thickness 0.15)
				)
				(justify left bottom)
				(hide yes)
			)
		)
		(property "Datasheet" "https://www.murata.com/products/productdetail?partno=GRM188R60J226MEA0%23"
			(at 134.62 139.7 0)
			(effects
				(font
					(size 1.27 1.27)
					(thickness 0.15)
				)
				(justify left bottom)
				(hide yes)
			)
		)
		(property "Description" ""
			(at 119.38 160.02 0)
			(effects
				(font
					(size 1.27 1.27)
				)
			)
		)
		(property "Manufacturer" "Murata"
			(at 139.7 139.7 0)
			(effects
				(font
					(size 1.27 1.27)
					(thickness 0.15)
				)
				(justify left bottom)
				(hide yes)
			)
		)
		(property "MPN" "GRM188R60J226MEA0D"
			(at 137.16 139.7 0)
			(effects
				(font
					(size 1.27 1.27)
					(thickness 0.15)
				)
				(justify left bottom)
				(hide yes)
			)
		)
		(property "Val" "22u"
			(at 120.015 159.385 90)
			(effects
				(font
					(size 1.27 1.27)
					(thickness 0.15)
				)
				(justify right)
			)
		)
		(property "License" "Apache-2.0"
			(at 142.24 139.7 0)
			(effects
				(font
					(size 1.27 1.27)
					(thickness 0.15)
				)
				(justify left bottom)
				(hide yes)
			)
		)
		(property "Author" "Antmicro"
			(at 144.78 139.7 0)
			(effects
				(font
					(size 1.27 1.27)
					(thickness 0.15)
				)
				(justify left bottom)
				(hide yes)
			)
		)
		(property "Voltage" ""
			(at 147.32 139.7 0)
			(effects
				(font
					(size 1.27 1.27)
				)
				(justify left bottom)
				(hide yes)
			)
		)
		(property "Dielectric" ""
			(at 149.86 139.7 0)
			(effects
				(font
					(size 1.27 1.27)
				)
				(justify left bottom)
				(hide yes)
			)
		)
		(pin "1"
		)
		(pin "2"
		)
		(instances
			(project "k410t-devboard"
				(path ""
					(reference "C329")
					(unit 1)
				)
			)
		)
	)
	(symbol
		(lib_id "antmicropower:+1V35")
		(at 281.94 219.71 0)
		(unit 1)
		(exclude_from_sim no)
		(in_bom yes)
		(on_board yes)
		(dnp no)
		(fields_autoplaced yes)
		(property "Reference" "#PWR0382"
			(at 281.94 223.52 0)
			(effects
				(font
					(size 1.27 1.27)
				)
				(hide yes)
			)
		)
		(property "Value" "+1V35"
			(at 281.94 216.154 0)
			(effects
				(font
					(size 1.27 1.27)
				)
			)
		)
		(property "Footprint" ""
			(at 281.94 219.71 0)
			(effects
				(font
					(size 1.27 1.27)
				)
				(hide yes)
			)
		)
		(property "Datasheet" ""
			(at 281.94 219.71 0)
			(effects
				(font
					(size 1.27 1.27)
				)
				(hide yes)
			)
		)
		(property "Description" ""
			(at 281.94 219.71 0)
			(effects
				(font
					(size 1.27 1.27)
				)
			)
		)
		(pin "1"
		)
		(instances
			(project "k410t-devboard"
				(path ""
					(reference "#PWR0382")
					(unit 1)
				)
			)
		)
	)
	(symbol
		(lib_id "antmicroResistors0402:R_47k_0402")
		(at 105.41 62.23 0)
		(unit 1)
		(exclude_from_sim no)
		(in_bom no)
		(on_board yes)
		(dnp yes)
		(property "Reference" "R283"
			(at 113.03 60.96 0)
			(effects
				(font
					(size 1.27 1.27)
				)
			)
		)
		(property "Value" "R_47k_0402"
			(at 125.73 74.93 0)
			(effects
				(font
					(size 1.27 1.27)
					(thickness 0.15)
				)
				(justify left bottom)
				(hide yes)
			)
		)
		(property "Footprint" "antmicro-footprints:R_0402_1005Metric"
			(at 125.73 77.47 0)
			(effects
				(font
					(size 1.27 1.27)
					(thickness 0.15)
				)
				(justify left bottom)
				(hide yes)
			)
		)
		(property "Datasheet" "https://www.bourns.com/docs/product-datasheets/cr.pdf"
			(at 125.73 80.01 0)
			(effects
				(font
					(size 1.27 1.27)
					(thickness 0.15)
				)
				(justify left bottom)
				(hide yes)
			)
		)
		(property "Description" ""
			(at 105.41 62.23 0)
			(effects
				(font
					(size 1.27 1.27)
				)
			)
		)
		(property "Manufacturer" "Bourns"
			(at 125.73 85.09 0)
			(effects
				(font
					(size 1.27 1.27)
					(thickness 0.15)
				)
				(justify left bottom)
				(hide yes)
			)
		)
		(property "MPN" "CR0402-FX-4702GLF"
			(at 125.73 82.55 0)
			(effects
				(font
					(size 1.27 1.27)
					(thickness 0.15)
				)
				(justify left bottom)
				(hide yes)
			)
		)
		(property "Val" "47k"
			(at 103.505 60.96 0)
			(effects
				(font
					(size 1.27 1.27)
					(thickness 0.15)
				)
			)
		)
		(property "DNP" "DNP"
			(at 107.95 62.23 0)
			(effects
				(font
					(size 1.27 1.27)
				)
			)
		)
		(property "License" "Apache-2.0"
			(at 125.73 87.63 0)
			(effects
				(font
					(size 1.27 1.27)
					(thickness 0.15)
				)
				(justify left bottom)
				(hide yes)
			)
		)
		(property "Author" "Antmicro"
			(at 125.73 90.17 0)
			(effects
				(font
					(size 1.27 1.27)
					(thickness 0.15)
				)
				(justify left bottom)
				(hide yes)
			)
		)
		(property "Tolerance" "1%"
			(at 125.73 72.39 0)
			(effects
				(font
					(size 1.27 1.27)
				)
				(justify left bottom)
				(hide yes)
			)
		)
		(pin "1"
		)
		(pin "2"
		)
		(instances
			(project "k410t-devboard"
				(path ""
					(reference "R283")
					(unit 1)
				)
			)
		)
	)
	(symbol
		(lib_id "antmicropower:GND")
		(at 119.38 233.68 0)
		(unit 1)
		(exclude_from_sim no)
		(in_bom yes)
		(on_board yes)
		(dnp no)
		(fields_autoplaced yes)
		(property "Reference" "#PWR0387"
			(at 119.38 240.03 0)
			(effects
				(font
					(size 1.27 1.27)
				)
				(hide yes)
			)
		)
		(property "Value" "GND"
			(at 119.38 237.49 0)
			(effects
				(font
					(size 1.27 1.27)
				)
			)
		)
		(property "Footprint" ""
			(at 128.27 241.3 0)
			(effects
				(font
					(size 1.27 1.27)
					(thickness 0.15)
				)
				(justify left bottom)
				(hide yes)
			)
		)
		(property "Datasheet" ""
			(at 128.27 246.38 0)
			(effects
				(font
					(size 1.27 1.27)
					(thickness 0.15)
				)
				(justify left bottom)
				(hide yes)
			)
		)
		(property "Description" ""
			(at 119.38 233.68 0)
			(effects
				(font
					(size 1.27 1.27)
				)
			)
		)
		(property "Author" "Antmicro"
			(at 128.27 241.3 0)
			(effects
				(font
					(size 1.27 1.27)
					(thickness 0.15)
				)
				(justify left bottom)
				(hide yes)
			)
		)
		(property "License" "Apache-2.0"
			(at 128.27 243.84 0)
			(effects
				(font
					(size 1.27 1.27)
					(thickness 0.15)
				)
				(justify left bottom)
				(hide yes)
			)
		)
		(pin "1"
		)
		(instances
			(project "k410t-devboard"
				(path ""
					(reference "#PWR0387")
					(unit 1)
				)
			)
		)
	)
	(symbol
		(lib_id "antmicropower:+1V2")
		(at 252.73 86.36 0)
		(unit 1)
		(exclude_from_sim no)
		(in_bom yes)
		(on_board yes)
		(dnp no)
		(property "Reference" "#PWR0379"
			(at 252.73 90.17 0)
			(effects
				(font
					(size 1.27 1.27)
				)
				(hide yes)
			)
		)
		(property "Value" "+1V2"
			(at 252.73 82.804 0)
			(effects
				(font
					(size 1.27 1.27)
				)
			)
		)
		(property "Footprint" ""
			(at 252.73 86.36 0)
			(effects
				(font
					(size 1.27 1.27)
				)
				(hide yes)
			)
		)
		(property "Datasheet" ""
			(at 252.73 86.36 0)
			(effects
				(font
					(size 1.27 1.27)
				)
				(hide yes)
			)
		)
		(property "Description" ""
			(at 252.73 86.36 0)
			(effects
				(font
					(size 1.27 1.27)
				)
			)
		)
		(pin "1"
		)
		(instances
			(project "k410t-devboard"
				(path ""
					(reference "#PWR0379")
					(unit 1)
				)
			)
		)
	)
	(symbol
		(lib_id "antmicroResistors0402:R_0R_0402")
		(at 242.57 198.12 90)
		(unit 1)
		(exclude_from_sim no)
		(in_bom yes)
		(on_board yes)
		(dnp no)
		(fields_autoplaced yes)
		(property "Reference" "R313"
			(at 244.475 194.3099 90)
			(effects
				(font
					(size 1.27 1.27)
				)
				(justify right)
			)
		)
		(property "Value" "R_0R_0402"
			(at 255.27 177.8 0)
			(effects
				(font
					(size 1.27 1.27)
					(thickness 0.15)
				)
				(justify left bottom)
				(hide yes)
			)
		)
		(property "Footprint" "antmicro-footprints:R_0402_1005Metric"
			(at 257.81 177.8 0)
			(effects
				(font
					(size 1.27 1.27)
					(thickness 0.15)
				)
				(justify left bottom)
				(hide yes)
			)
		)
		(property "Datasheet" "https://industrial.panasonic.com/cdbs/www-data/pdf/RDA0000/AOA0000C301.pdf"
			(at 260.35 177.8 0)
			(effects
				(font
					(size 1.27 1.27)
					(thickness 0.15)
				)
				(justify left bottom)
				(hide yes)
			)
		)
		(property "Description" ""
			(at 242.57 198.12 0)
			(effects
				(font
					(size 1.27 1.27)
				)
			)
		)
		(property "Manufacturer" "Panasonic"
			(at 265.43 177.8 0)
			(effects
				(font
					(size 1.27 1.27)
					(thickness 0.15)
				)
				(justify left bottom)
				(hide yes)
			)
		)
		(property "MPN" "ERJ2GE0R00X"
			(at 262.89 177.8 0)
			(effects
				(font
					(size 1.27 1.27)
					(thickness 0.15)
				)
				(justify left bottom)
				(hide yes)
			)
		)
		(property "Val" "0R"
			(at 244.475 196.8499 90)
			(effects
				(font
					(size 1.27 1.27)
					(thickness 0.15)
				)
				(justify right)
			)
		)
		(property "License" "Apache-2.0"
			(at 267.97 177.8 0)
			(effects
				(font
					(size 1.27 1.27)
					(thickness 0.15)
				)
				(justify left bottom)
				(hide yes)
			)
		)
		(property "Author" "Antmicro"
			(at 270.51 177.8 0)
			(effects
				(font
					(size 1.27 1.27)
					(thickness 0.15)
				)
				(justify left bottom)
				(hide yes)
			)
		)
		(property "Tolerance" "~"
			(at 252.73 177.8 0)
			(effects
				(font
					(size 1.27 1.27)
				)
				(justify left bottom)
				(hide yes)
			)
		)
		(property "Current" "1A"
			(at 244.475 198.1199 90)
			(effects
				(font
					(size 1.27 1.27)
					(thickness 0.15)
				)
				(justify right)
				(hide yes)
			)
		)
		(pin "1"
		)
		(pin "2"
		)
		(instances
			(project "k410t-devboard"
				(path ""
					(reference "R313")
					(unit 1)
				)
			)
		)
	)
	(symbol
		(lib_id "k410t-devboard:Net-Tie_2")
		(at 113.03 38.1 0)
		(unit 1)
		(exclude_from_sim no)
		(in_bom yes)
		(on_board yes)
		(dnp no)
		(fields_autoplaced yes)
		(property "Reference" "NT39"
			(at 113.03 36.83 0)
			(effects
				(font
					(size 1.27 1.27)
				)
				(hide yes)
			)
		)
		(property "Value" "Net-Tie_2"
			(at 114.935 35.56 0)
			(effects
				(font
					(size 1.27 1.27)
					(thickness 0.15)
				)
				(hide yes)
			)
		)
		(property "Footprint" "antmicro-footprints:NetTie-2_SMD_Pad0.127mm"
			(at 134.62 43.18 0)
			(effects
				(font
					(size 1.27 1.27)
					(thickness 0.15)
				)
				(justify left bottom)
				(hide yes)
			)
		)
		(property "Datasheet" ""
			(at 134.62 45.72 0)
			(effects
				(font
					(size 1.27 1.27)
					(thickness 0.15)
				)
				(justify left bottom)
				(hide yes)
			)
		)
		(property "Description" ""
			(at 113.03 38.1 0)
			(effects
				(font
					(size 1.27 1.27)
				)
			)
		)
		(property "MPN" ""
			(at 134.62 46.99 0)
			(effects
				(font
					(size 1.27 1.27)
				)
				(justify left)
				(hide yes)
			)
		)
		(property "Manufacturer" ""
			(at 134.62 49.53 0)
			(effects
				(font
					(size 1.27 1.27)
				)
				(justify left)
				(hide yes)
			)
		)
		(property "Author" "Antmicro"
			(at 134.62 53.34 0)
			(effects
				(font
					(size 1.27 1.27)
					(thickness 0.15)
				)
				(justify left bottom)
				(hide yes)
			)
		)
		(property "License" "Apache-2.0"
			(at 134.62 55.88 0)
			(effects
				(font
					(size 1.27 1.27)
					(thickness 0.15)
				)
				(justify left bottom)
				(hide yes)
			)
		)
		(pin "1"
		)
		(pin "2"
		)
		(instances
			(project "k410t-devboard"
				(path ""
					(reference "NT39")
					(unit 1)
				)
			)
		)
	)
	(symbol
		(lib_id "antmicroCapacitors0402:C_1u_0402")
		(at 55.88 49.53 90)
		(unit 1)
		(exclude_from_sim no)
		(in_bom yes)
		(on_board yes)
		(dnp no)
		(property "Reference" "C321"
			(at 56.515 45.085 90)
			(effects
				(font
					(size 1.27 1.27)
				)
				(justify right)
			)
		)
		(property "Value" "C_1u_0402"
			(at 66.04 29.21 0)
			(effects
				(font
					(size 1.27 1.27)
					(thickness 0.15)
				)
				(justify left bottom)
				(hide yes)
			)
		)
		(property "Footprint" "antmicro-footprints:C_0402_1005Metric"
			(at 68.58 29.21 0)
			(effects
				(font
					(size 1.27 1.27)
					(thickness 0.15)
				)
				(justify left bottom)
				(hide yes)
			)
		)
		(property "Datasheet" "https://product.tdk.com/en/search/capacitor/ceramic/mlcc/info?part_no=C1005X6S1A105K050BC"
			(at 71.12 29.21 0)
			(effects
				(font
					(size 1.27 1.27)
					(thickness 0.15)
				)
				(justify left bottom)
				(hide yes)
			)
		)
		(property "Description" ""
			(at 55.88 49.53 0)
			(effects
				(font
					(size 1.27 1.27)
				)
			)
		)
		(property "Manufacturer" "TDK"
			(at 76.2 29.21 0)
			(effects
				(font
					(size 1.27 1.27)
					(thickness 0.15)
				)
				(justify left bottom)
				(hide yes)
			)
		)
		(property "MPN" "C1005X6S1A105K050BC"
			(at 73.66 29.21 0)
			(effects
				(font
					(size 1.27 1.27)
					(thickness 0.15)
				)
				(justify left bottom)
				(hide yes)
			)
		)
		(property "Val" "1u"
			(at 56.515 48.895 90)
			(effects
				(font
					(size 1.27 1.27)
					(thickness 0.15)
				)
				(justify right)
			)
		)
		(property "License" "Apache-2.0"
			(at 78.74 29.21 0)
			(effects
				(font
					(size 1.27 1.27)
					(thickness 0.15)
				)
				(justify left bottom)
				(hide yes)
			)
		)
		(property "Author" "Antmicro"
			(at 81.28 29.21 0)
			(effects
				(font
					(size 1.27 1.27)
					(thickness 0.15)
				)
				(justify left bottom)
				(hide yes)
			)
		)
		(property "Voltage" ""
			(at 83.82 29.21 0)
			(effects
				(font
					(size 1.27 1.27)
				)
				(justify left bottom)
				(hide yes)
			)
		)
		(property "Dielectric" ""
			(at 86.36 29.21 0)
			(effects
				(font
					(size 1.27 1.27)
				)
				(justify left bottom)
				(hide yes)
			)
		)
		(pin "1"
		)
		(pin "2"
		)
		(instances
			(project "k410t-devboard"
				(path ""
					(reference "C321")
					(unit 1)
				)
			)
		)
	)
	(symbol
		(lib_id "antmicroTestPoints:TP_0.75mm_SMD")
		(at 71.12 133.35 270)
		(unit 1)
		(exclude_from_sim no)
		(in_bom yes)
		(on_board yes)
		(dnp no)
		(property "Reference" "TP6"
			(at 73.025 138.43 90)
			(effects
				(font
					(size 1.27 1.27)
				)
				(justify right)
			)
		)
		(property "Value" "TP_0.75mm_SMD"
			(at 68.58 133.35 0)
			(effects
				(font
					(size 1.27 1.27)
				)
				(hide yes)
			)
		)
		(property "Footprint" "antmicro-footprints:TP_SMD_0.75mm"
			(at 76.2 138.43 0)
			(effects
				(font
					(size 1.27 1.27)
				)
				(justify left)
				(hide yes)
			)
		)
		(property "Datasheet" ""
			(at 78.74 138.43 0)
			(effects
				(font
					(size 1.27 1.27)
				)
				(justify left)
				(hide yes)
			)
		)
		(property "Description" ""
			(at 71.12 133.35 0)
			(effects
				(font
					(size 1.27 1.27)
				)
			)
		)
		(property "MPN" ""
			(at 71.12 133.35 0)
			(effects
				(font
					(size 1.27 1.27)
				)
				(hide yes)
			)
		)
		(property "Manufacturer" ""
			(at 71.12 133.35 0)
			(effects
				(font
					(size 1.27 1.27)
				)
				(hide yes)
			)
		)
		(property "Author" "Antmicro"
			(at 55.88 148.59 0)
			(effects
				(font
					(size 1.27 1.27)
					(thickness 0.15)
				)
				(justify left bottom)
				(hide yes)
			)
		)
		(property "License" "Apache-2.0"
			(at 53.34 148.59 0)
			(effects
				(font
					(size 1.27 1.27)
					(thickness 0.15)
				)
				(justify left bottom)
				(hide yes)
			)
		)
		(pin "1"
		)
		(instances
			(project "k410t-devboard"
				(path ""
					(reference "TP6")
					(unit 1)
				)
			)
		)
	)
	(symbol
		(lib_id "antmicroCapacitorsmisc:C_22u_25V_0805")
		(at 49.53 189.23 90)
		(unit 1)
		(exclude_from_sim no)
		(in_bom yes)
		(on_board yes)
		(dnp no)
		(property "Reference" "C317"
			(at 50.8 184.15 90)
			(effects
				(font
					(size 1.27 1.27)
				)
				(justify right)
			)
		)
		(property "Value" "C_22u_25V_0805"
			(at 53.34 189.23 0)
			(effects
				(font
					(size 1.27 1.27)
				)
				(hide yes)
			)
		)
		(property "Footprint" "antmicro-footprints:C_0805_2012Metric"
			(at 44.45 184.15 0)
			(effects
				(font
					(size 1.27 1.27)
				)
				(justify left)
				(hide yes)
			)
		)
		(property "Datasheet" "https://product.samsungsem.com/mlcc/CL21A226MAYNNN.do"
			(at 49.53 189.23 0)
			(effects
				(font
					(size 1.27 1.27)
				)
				(hide yes)
			)
		)
		(property "Description" ""
			(at 49.53 189.23 0)
			(effects
				(font
					(size 1.27 1.27)
				)
			)
		)
		(property "Manufacturer" "Samsung Electro-Mechanics"
			(at 39.37 184.15 0)
			(effects
				(font
					(size 1.27 1.27)
				)
				(justify left)
				(hide yes)
			)
		)
		(property "MPN" "CL21A226MAYNNNE"
			(at 41.91 184.15 0)
			(effects
				(font
					(size 1.27 1.27)
				)
				(justify left)
				(hide yes)
			)
		)
		(property "Val" "22u"
			(at 50.8 187.96 90)
			(effects
				(font
					(size 1.27 1.27)
				)
				(justify right)
			)
		)
		(property "License" "Apache-2.0"
			(at 72.39 168.91 0)
			(effects
				(font
					(size 1.27 1.27)
					(thickness 0.15)
				)
				(justify left bottom)
				(hide yes)
			)
		)
		(property "Author" "Antmicro"
			(at 74.93 168.91 0)
			(effects
				(font
					(size 1.27 1.27)
					(thickness 0.15)
				)
				(justify left bottom)
				(hide yes)
			)
		)
		(property "Voltage" "25V"
			(at 50.8 190.5 90)
			(effects
				(font
					(size 1.27 1.27)
				)
				(justify right)
			)
		)
		(property "Dielectric" "X5R"
			(at 80.01 168.91 0)
			(effects
				(font
					(size 1.27 1.27)
				)
				(justify left bottom)
				(hide yes)
			)
		)
		(pin "1"
		)
		(pin "2"
		)
		(instances
			(project "k410t-devboard"
				(path ""
					(reference "C317")
					(unit 1)
				)
			)
		)
	)
	(symbol
		(lib_id "antmicroCapacitors0603:C_22u_0603")
		(at 119.38 123.19 90)
		(unit 1)
		(exclude_from_sim no)
		(in_bom yes)
		(on_board yes)
		(dnp no)
		(property "Reference" "C327"
			(at 120.015 118.745 90)
			(effects
				(font
					(size 1.27 1.27)
				)
				(justify right)
			)
		)
		(property "Value" "C_22u_0603"
			(at 129.54 102.87 0)
			(effects
				(font
					(size 1.27 1.27)
					(thickness 0.15)
				)
				(justify left bottom)
				(hide yes)
			)
		)
		(property "Footprint" "antmicro-footprints:C_0603_1608Metric"
			(at 132.08 102.87 0)
			(effects
				(font
					(size 1.27 1.27)
					(thickness 0.15)
				)
				(justify left bottom)
				(hide yes)
			)
		)
		(property "Datasheet" "https://www.murata.com/products/productdetail?partno=GRM188R60J226MEA0%23"
			(at 134.62 102.87 0)
			(effects
				(font
					(size 1.27 1.27)
					(thickness 0.15)
				)
				(justify left bottom)
				(hide yes)
			)
		)
		(property "Description" ""
			(at 119.38 123.19 0)
			(effects
				(font
					(size 1.27 1.27)
				)
			)
		)
		(property "Manufacturer" "Murata"
			(at 139.7 102.87 0)
			(effects
				(font
					(size 1.27 1.27)
					(thickness 0.15)
				)
				(justify left bottom)
				(hide yes)
			)
		)
		(property "MPN" "GRM188R60J226MEA0D"
			(at 137.16 102.87 0)
			(effects
				(font
					(size 1.27 1.27)
					(thickness 0.15)
				)
				(justify left bottom)
				(hide yes)
			)
		)
		(property "Val" "22u"
			(at 120.015 122.555 90)
			(effects
				(font
					(size 1.27 1.27)
					(thickness 0.15)
				)
				(justify right)
			)
		)
		(property "License" "Apache-2.0"
			(at 142.24 102.87 0)
			(effects
				(font
					(size 1.27 1.27)
					(thickness 0.15)
				)
				(justify left bottom)
				(hide yes)
			)
		)
		(property "Author" "Antmicro"
			(at 144.78 102.87 0)
			(effects
				(font
					(size 1.27 1.27)
					(thickness 0.15)
				)
				(justify left bottom)
				(hide yes)
			)
		)
		(property "Voltage" ""
			(at 147.32 102.87 0)
			(effects
				(font
					(size 1.27 1.27)
				)
				(justify left bottom)
				(hide yes)
			)
		)
		(property "Dielectric" ""
			(at 149.86 102.87 0)
			(effects
				(font
					(size 1.27 1.27)
				)
				(justify left bottom)
				(hide yes)
			)
		)
		(pin "1"
		)
		(pin "2"
		)
		(instances
			(project "k410t-devboard"
				(path ""
					(reference "C327")
					(unit 1)
				)
			)
		)
	)
)
